G04 ================== begin FILE IDENTIFICATION RECORD ==================*
G04 Layout Name:  D:/<user>/Wistron_project/16316-1/gbr-0621/16316-1.brd*
G04 Film Name:    L4VCC*
G04 File Format:  Gerber RS274X*
G04 File Origin:  Cadence Allegro 16.5-S056*
G04 Origin Date:  Wed Jun 21 09:32:08 2017*
G04 *
G04 Layer:  VIA CLASS/L4VCC*
G04 Layer:  PIN/L4VCC*
G04 Layer:  PACKAGE GEOMETRY/PWRVCC*
G04 Layer:  ETCH/L4VCC*
G04 Layer:  DRAWING FORMAT/LAYER_PCB_STORY*
G04 Layer:  DRAWING FORMAT/LAYER_L4VCC*
G04 *
G04 Offset:    (0.00 0.00)*
G04 Mirror:    No*
G04 Mode:      Negative*
G04 Rotation:  0*
G04 FullContactRelief:  No*
G04 UndefLineWidth:     6.00*
G04 ================== end FILE IDENTIFICATION RECORD ====================*
%FSLAX35Y35*MOIN*%
%IR0*IPPOS*OFA0.00000B0.00000*MIA0B0*SFA1.00000B1.00000*%
%ADD12C,.03*%
%ADD15C,.032*%
%ADD34C,.034*%
%ADD28C,.043*%
%ADD23C,.07*%
%ADD17C,.09*%
%ADD11C,.036*%
%ADD30C,.028*%
%AMMACRO22*
4,1,15,.00398,.00044,
.003999,.000208,
.004004,-.000025,
.003996,-.000258,
.00398,-.00044,
.00483,-.00129,
.004897,-.001007,
.004947,-.000721,
.004981,-.000432,
.004997,-.000141,
.004997,.000149,
.00498,.00044,
.004946,.000729,
.004895,.001015,
.00483,.00129,
.00398,.00044,
90.*
4,1,15,.00044,-.00398,
.000208,-.003999,
-.000025,-.004004,
-.000258,-.003996,
-.00044,-.00398,
-.00129,-.00483,
-.001007,-.004897,
-.000721,-.004947,
-.000432,-.004981,
-.000141,-.004997,
.000149,-.004997,
.00044,-.00498,
.000729,-.004946,
.001015,-.004895,
.00129,-.00483,
.00044,-.00398,
90.*
4,1,15,-.00398,-.00044,
-.003999,-.000208,
-.004004,.000025,
-.003996,.000258,
-.00398,.00044,
-.00483,.00129,
-.004897,.001007,
-.004947,.000721,
-.004981,.000432,
-.004997,.000141,
-.004997,-.000149,
-.00498,-.00044,
-.004946,-.000729,
-.004895,-.001015,
-.00483,-.00129,
-.00398,-.00044,
90.*
4,1,15,-.00044,.00398,
-.000208,.003999,
.000025,.004004,
.000258,.003996,
.00044,.00398,
.00129,.00483,
.001007,.004897,
.000721,.004947,
.000432,.004981,
.000141,.004997,
-.000149,.004997,
-.00044,.00498,
-.000729,.004946,
-.001015,.004895,
-.00129,.00483,
-.00044,.00398,
90.*
%
%ADD22MACRO22*%
%AMMACRO24*
4,1,15,-.00398,.00044,
-.003999,.000208,
-.004004,-.000025,
-.003996,-.000258,
-.00398,-.00044,
-.00483,-.00129,
-.004897,-.001007,
-.004947,-.000721,
-.004981,-.000432,
-.004997,-.000141,
-.004997,.000149,
-.00498,.00044,
-.004946,.000729,
-.004895,.001015,
-.00483,.00129,
-.00398,.00044,
90.*
4,1,15,-.00044,-.00398,
-.000208,-.003999,
.000025,-.004004,
.000258,-.003996,
.00044,-.00398,
.00129,-.00483,
.001007,-.004897,
.000721,-.004947,
.000432,-.004981,
.000141,-.004997,
-.000149,-.004997,
-.00044,-.00498,
-.000729,-.004946,
-.001015,-.004895,
-.00129,-.00483,
-.00044,-.00398,
90.*
4,1,15,.00398,-.00044,
.003999,-.000208,
.004004,.000025,
.003996,.000258,
.00398,.00044,
.00483,.00129,
.004897,.001007,
.004947,.000721,
.004981,.000432,
.004997,.000141,
.004997,-.000149,
.00498,-.00044,
.004946,-.000729,
.004895,-.001015,
.00483,-.00129,
.00398,-.00044,
90.*
4,1,15,.00044,.00398,
.000208,.003999,
-.000025,.004004,
-.000258,.003996,
-.00044,.00398,
-.00129,.00483,
-.001007,.004897,
-.000721,.004947,
-.000432,.004981,
-.000141,.004997,
.000149,.004997,
.00044,.00498,
.000729,.004946,
.001015,.004895,
.00129,.00483,
.00044,.00398,
90.*
%
%ADD24MACRO24*%
%AMMACRO13*
4,1,15,.00398,.00044,
.003999,.000208,
.004004,-.000025,
.003996,-.000258,
.00398,-.00044,
.00483,-.00129,
.004897,-.001007,
.004947,-.000721,
.004981,-.000432,
.004997,-.000141,
.004997,.000149,
.00498,.00044,
.004946,.000729,
.004895,.001015,
.00483,.00129,
.00398,.00044,
0.0*
4,1,15,.00044,-.00398,
.000208,-.003999,
-.000025,-.004004,
-.000258,-.003996,
-.00044,-.00398,
-.00129,-.00483,
-.001007,-.004897,
-.000721,-.004947,
-.000432,-.004981,
-.000141,-.004997,
.000149,-.004997,
.00044,-.00498,
.000729,-.004946,
.001015,-.004895,
.00129,-.00483,
.00044,-.00398,
0.0*
4,1,15,-.00398,-.00044,
-.003999,-.000208,
-.004004,.000025,
-.003996,.000258,
-.00398,.00044,
-.00483,.00129,
-.004897,.001007,
-.004947,.000721,
-.004981,.000432,
-.004997,.000141,
-.004997,-.000149,
-.00498,-.00044,
-.004946,-.000729,
-.004895,-.001015,
-.00483,-.00129,
-.00398,-.00044,
0.0*
4,1,15,-.00044,.00398,
-.000208,.003999,
.000025,.004004,
.000258,.003996,
.00044,.00398,
.00129,.00483,
.001007,.004897,
.000721,.004947,
.000432,.004981,
.000141,.004997,
-.000149,.004997,
-.00044,.00498,
-.000729,.004946,
-.001015,.004895,
-.00129,.00483,
-.00044,.00398,
0.0*
%
%ADD13MACRO13*%
%AMMACRO25*
4,1,15,-.00398,.00044,
-.003999,.000208,
-.004004,-.000025,
-.003996,-.000258,
-.00398,-.00044,
-.00483,-.00129,
-.004897,-.001007,
-.004947,-.000721,
-.004981,-.000432,
-.004997,-.000141,
-.004997,.000149,
-.00498,.00044,
-.004946,.000729,
-.004895,.001015,
-.00483,.00129,
-.00398,.00044,
0.0*
4,1,15,-.00044,-.00398,
-.000208,-.003999,
.000025,-.004004,
.000258,-.003996,
.00044,-.00398,
.00129,-.00483,
.001007,-.004897,
.000721,-.004947,
.000432,-.004981,
.000141,-.004997,
-.000149,-.004997,
-.00044,-.00498,
-.000729,-.004946,
-.001015,-.004895,
-.00129,-.00483,
-.00044,-.00398,
0.0*
4,1,15,.00398,-.00044,
.003999,-.000208,
.004004,.000025,
.003996,.000258,
.00398,.00044,
.00483,.00129,
.004897,.001007,
.004947,.000721,
.004981,.000432,
.004997,.000141,
.004997,-.000149,
.00498,-.00044,
.004946,-.000729,
.004895,-.001015,
.00483,-.00129,
.00398,-.00044,
0.0*
4,1,15,.00044,.00398,
.000208,.003999,
-.000025,.004004,
-.000258,.003996,
-.00044,.00398,
-.00129,.00483,
-.001007,.004897,
-.000721,.004947,
-.000432,.004981,
-.000141,.004997,
.000149,.004997,
.00044,.00498,
.000729,.004946,
.001015,.004895,
.00129,.00483,
.00044,.00398,
0.0*
%
%ADD25MACRO25*%
%ADD18C,.111*%
%ADD19C,.122*%
%ADD10C,.114*%
%ADD31C,.115*%
%ADD20C,.125*%
%ADD29C,.147*%
%ADD16C,.186*%
%ADD27C,.178*%
%AMMACRO33*
4,1,15,.00398,.00044,
.003999,.000208,
.004004,-.000025,
.003996,-.000258,
.00398,-.00044,
.00483,-.00129,
.004897,-.001007,
.004947,-.000721,
.004981,-.000432,
.004997,-.000141,
.004997,.000149,
.00498,.00044,
.004946,.000729,
.004895,.001015,
.00483,.00129,
.00398,.00044,
315.*
4,1,15,.00044,-.00398,
.000208,-.003999,
-.000025,-.004004,
-.000258,-.003996,
-.00044,-.00398,
-.00129,-.00483,
-.001007,-.004897,
-.000721,-.004947,
-.000432,-.004981,
-.000141,-.004997,
.000149,-.004997,
.00044,-.00498,
.000729,-.004946,
.001015,-.004895,
.00129,-.00483,
.00044,-.00398,
315.*
4,1,15,-.00398,-.00044,
-.003999,-.000208,
-.004004,.000025,
-.003996,.000258,
-.00398,.00044,
-.00483,.00129,
-.004897,.001007,
-.004947,.000721,
-.004981,.000432,
-.004997,.000141,
-.004997,-.000149,
-.00498,-.00044,
-.004946,-.000729,
-.004895,-.001015,
-.00483,-.00129,
-.00398,-.00044,
315.*
4,1,15,-.00044,.00398,
-.000208,.003999,
.000025,.004004,
.000258,.003996,
.00044,.00398,
.00129,.00483,
.001007,.004897,
.000721,.004947,
.000432,.004981,
.000141,.004997,
-.000149,.004997,
-.00044,.00498,
-.000729,.004946,
-.001015,.004895,
-.00129,.00483,
-.00044,.00398,
315.*
%
%ADD33MACRO33*%
%AMMACRO32*
4,1,15,.00398,.00044,
.003999,.000208,
.004004,-.000025,
.003996,-.000258,
.00398,-.00044,
.00483,-.00129,
.004897,-.001007,
.004947,-.000721,
.004981,-.000432,
.004997,-.000141,
.004997,.000149,
.00498,.00044,
.004946,.000729,
.004895,.001015,
.00483,.00129,
.00398,.00044,
225.*
4,1,15,.00044,-.00398,
.000208,-.003999,
-.000025,-.004004,
-.000258,-.003996,
-.00044,-.00398,
-.00129,-.00483,
-.001007,-.004897,
-.000721,-.004947,
-.000432,-.004981,
-.000141,-.004997,
.000149,-.004997,
.00044,-.00498,
.000729,-.004946,
.001015,-.004895,
.00129,-.00483,
.00044,-.00398,
225.*
4,1,15,-.00398,-.00044,
-.003999,-.000208,
-.004004,.000025,
-.003996,.000258,
-.00398,.00044,
-.00483,.00129,
-.004897,.001007,
-.004947,.000721,
-.004981,.000432,
-.004997,.000141,
-.004997,-.000149,
-.00498,-.00044,
-.004946,-.000729,
-.004895,-.001015,
-.00483,-.00129,
-.00398,-.00044,
225.*
4,1,15,-.00044,.00398,
-.000208,.003999,
.000025,.004004,
.000258,.003996,
.00044,.00398,
.00129,.00483,
.001007,.004897,
.000721,.004947,
.000432,.004981,
.000141,.004997,
-.000149,.004997,
-.00044,.00498,
-.000729,.004946,
-.001015,.004895,
-.00129,.00483,
-.00044,.00398,
225.*
%
%ADD32MACRO32*%
%AMMACRO21*
4,1,15,.00398,.00044,
.003999,.000208,
.004004,-.000025,
.003996,-.000258,
.00398,-.00044,
.00483,-.00129,
.004897,-.001007,
.004947,-.000721,
.004981,-.000432,
.004997,-.000141,
.004997,.000149,
.00498,.00044,
.004946,.000729,
.004895,.001015,
.00483,.00129,
.00398,.00044,
270.*
4,1,15,.00044,-.00398,
.000208,-.003999,
-.000025,-.004004,
-.000258,-.003996,
-.00044,-.00398,
-.00129,-.00483,
-.001007,-.004897,
-.000721,-.004947,
-.000432,-.004981,
-.000141,-.004997,
.000149,-.004997,
.00044,-.00498,
.000729,-.004946,
.001015,-.004895,
.00129,-.00483,
.00044,-.00398,
270.*
4,1,15,-.00398,-.00044,
-.003999,-.000208,
-.004004,.000025,
-.003996,.000258,
-.00398,.00044,
-.00483,.00129,
-.004897,.001007,
-.004947,.000721,
-.004981,.000432,
-.004997,.000141,
-.004997,-.000149,
-.00498,-.00044,
-.004946,-.000729,
-.004895,-.001015,
-.00483,-.00129,
-.00398,-.00044,
270.*
4,1,15,-.00044,.00398,
-.000208,.003999,
.000025,.004004,
.000258,.003996,
.00044,.00398,
.00129,.00483,
.001007,.004897,
.000721,.004947,
.000432,.004981,
.000141,.004997,
-.000149,.004997,
-.00044,.00498,
-.000729,.004946,
-.001015,.004895,
-.00129,.00483,
-.00044,.00398,
270.*
%
%ADD21MACRO21*%
%AMMACRO14*
4,1,15,.00398,.00044,
.003999,.000208,
.004004,-.000025,
.003996,-.000258,
.00398,-.00044,
.00483,-.00129,
.004897,-.001007,
.004947,-.000721,
.004981,-.000432,
.004997,-.000141,
.004997,.000149,
.00498,.00044,
.004946,.000729,
.004895,.001015,
.00483,.00129,
.00398,.00044,
180.*
4,1,15,.00044,-.00398,
.000208,-.003999,
-.000025,-.004004,
-.000258,-.003996,
-.00044,-.00398,
-.00129,-.00483,
-.001007,-.004897,
-.000721,-.004947,
-.000432,-.004981,
-.000141,-.004997,
.000149,-.004997,
.00044,-.00498,
.000729,-.004946,
.001015,-.004895,
.00129,-.00483,
.00044,-.00398,
180.*
4,1,15,-.00398,-.00044,
-.003999,-.000208,
-.004004,.000025,
-.003996,.000258,
-.00398,.00044,
-.00483,.00129,
-.004897,.001007,
-.004947,.000721,
-.004981,.000432,
-.004997,.000141,
-.004997,-.000149,
-.00498,-.00044,
-.004946,-.000729,
-.004895,-.001015,
-.00483,-.00129,
-.00398,-.00044,
180.*
4,1,15,-.00044,.00398,
-.000208,.003999,
.000025,.004004,
.000258,.003996,
.00044,.00398,
.00129,.00483,
.001007,.004897,
.000721,.004947,
.000432,.004981,
.000141,.004997,
-.000149,.004997,
-.00044,.00498,
-.000729,.004946,
-.001015,.004895,
-.00129,.00483,
-.00044,.00398,
180.*
%
%ADD14MACRO14*%
%AMMACRO26*
4,1,15,-.00398,.00044,
-.003999,.000208,
-.004004,-.000025,
-.003996,-.000258,
-.00398,-.00044,
-.00483,-.00129,
-.004897,-.001007,
-.004947,-.000721,
-.004981,-.000432,
-.004997,-.000141,
-.004997,.000149,
-.00498,.00044,
-.004946,.000729,
-.004895,.001015,
-.00483,.00129,
-.00398,.00044,
270.*
4,1,15,-.00044,-.00398,
-.000208,-.003999,
.000025,-.004004,
.000258,-.003996,
.00044,-.00398,
.00129,-.00483,
.001007,-.004897,
.000721,-.004947,
.000432,-.004981,
.000141,-.004997,
-.000149,-.004997,
-.00044,-.00498,
-.000729,-.004946,
-.001015,-.004895,
-.00129,-.00483,
-.00044,-.00398,
270.*
4,1,15,.00398,-.00044,
.003999,-.000208,
.004004,.000025,
.003996,.000258,
.00398,.00044,
.00483,.00129,
.004897,.001007,
.004947,.000721,
.004981,.000432,
.004997,.000141,
.004997,-.000149,
.00498,-.00044,
.004946,-.000729,
.004895,-.001015,
.00483,-.00129,
.00398,-.00044,
270.*
4,1,15,.00044,.00398,
.000208,.003999,
-.000025,.004004,
-.000258,.003996,
-.00044,.00398,
-.00129,.00483,
-.001007,.004897,
-.000721,.004947,
-.000432,.004981,
-.000141,.004997,
.000149,.004997,
.00044,.00498,
.000729,.004946,
.001015,.004895,
.00129,.00483,
.00044,.00398,
270.*
%
%ADD26MACRO26*%
%AMMACRO35*
4,1,15,.00398,.00044,
.003999,.000208,
.004004,-.000025,
.003996,-.000258,
.00398,-.00044,
.00483,-.00129,
.004897,-.001007,
.004947,-.000721,
.004981,-.000432,
.004997,-.000141,
.004997,.000149,
.00498,.00044,
.004946,.000729,
.004895,.001015,
.00483,.00129,
.00398,.00044,
282.*
4,1,15,.00044,-.00398,
.000208,-.003999,
-.000025,-.004004,
-.000258,-.003996,
-.00044,-.00398,
-.00129,-.00483,
-.001007,-.004897,
-.000721,-.004947,
-.000432,-.004981,
-.000141,-.004997,
.000149,-.004997,
.00044,-.00498,
.000729,-.004946,
.001015,-.004895,
.00129,-.00483,
.00044,-.00398,
282.*
4,1,15,-.00398,-.00044,
-.003999,-.000208,
-.004004,.000025,
-.003996,.000258,
-.00398,.00044,
-.00483,.00129,
-.004897,.001007,
-.004947,.000721,
-.004981,.000432,
-.004997,.000141,
-.004997,-.000149,
-.00498,-.00044,
-.004946,-.000729,
-.004895,-.001015,
-.00483,-.00129,
-.00398,-.00044,
282.*
4,1,15,-.00044,.00398,
-.000208,.003999,
.000025,.004004,
.000258,.003996,
.00044,.00398,
.00129,.00483,
.001007,.004897,
.000721,.004947,
.000432,.004981,
.000141,.004997,
-.000149,.004997,
-.00044,.00498,
-.000729,.004946,
-.001015,.004895,
-.00129,.00483,
-.00044,.00398,
282.*
%
%ADD35MACRO35*%
%ADD36C,.02*%
%ADD37C,.006*%
%ADD41C,.06604*%
%ADD38C,.11004*%
%ADD43C,.11104*%
%ADD40C,.11804*%
%ADD46C,.23626*%
%ADD42C,.37405*%
%ADD45C,.23627*%
%ADD44C,.37406*%
%ADD39C,.27563*%
G75*
%LPD*%
G75*
G36*
G01X-6000Y-6000D02*
X832772D01*
Y576866D01*
X-6000D01*
Y-6000D01*
G37*
%LPC*%
G75*
G36*
G01X5000Y142616D02*
X130238D01*
X132307Y140547D01*
Y110315D01*
X150938Y91684D01*
Y6909D01*
X149029Y5000D01*
X7874D01*
G02X5000Y7874I0J2874D01*
G01Y142616D01*
G37*
G36*
G01X660650Y419003D02*
X680860Y398793D01*
Y304121D01*
X678889Y302150D01*
X622111D01*
X620850Y303411D01*
Y373141D01*
X618871Y375120D01*
X545121D01*
X536531Y383710D01*
X526649D01*
X519529Y376590D01*
X202089D01*
X199250Y373751D01*
Y347411D01*
X198589Y346750D01*
X140483D01*
X123444Y329711D01*
Y245797D01*
X132307Y236934D01*
Y146185D01*
X130238Y144116D01*
X5000D01*
Y562992D01*
G02X7874Y565866I2874J0D01*
G01X326783D01*
G02X329656Y562992I-1J-2874D01*
G01Y520720D01*
G03X350441Y496345I24685J0D01*
G01X383461Y491063D01*
X443310D01*
X476350Y496348D01*
G03X497136Y520723I-3899J24375D01*
G01Y562992D01*
G02X500010Y565866I2874J0D01*
G01X658943D01*
X660010Y564799D01*
X660023Y564745D01*
G03X660650Y563588I2527J621D01*
G01Y419003D01*
G37*
G36*
G01X154311Y5000D02*
X152438Y6873D01*
Y92306D01*
X133807Y110937D01*
Y145563D01*
X133808Y145564D01*
Y146186D01*
X133807Y146187D01*
Y237556D01*
X124944Y246419D01*
Y329089D01*
X141105Y345250D01*
X198789D01*
X199250Y344789D01*
Y217140D01*
G03X199497Y216543I850J2D01*
G03X199499Y216541I531J529D01*
G01X232950Y183089D01*
Y134189D01*
X235289Y131850D01*
X320726D01*
X320740Y131848D01*
G03X321362I311J2180D01*
G01X321376Y131850D01*
X334889D01*
X348489Y118250D01*
X561492D01*
X564021Y120779D01*
Y182880D01*
X560168Y186733D01*
Y300387D01*
X554605Y305950D01*
X480311D01*
X479136Y307125D01*
Y374375D01*
X479851Y375090D01*
X519764D01*
G02X520148Y374579I0J-400D01*
G03X542972Y374098I11348J-3280D01*
G02X543644Y374475I389J95D01*
G01X544499Y373620D01*
X618249D01*
X619350Y372519D01*
Y299959D01*
X608293Y288902D01*
Y120427D01*
G02X607518Y120287I-400J0D01*
G03Y111997I-11062J-4145D01*
G02X608293Y111857I375J-140D01*
G01Y109744D01*
X614287Y103750D01*
X697889D01*
X699789Y101850D01*
X820502D01*
X821772Y100580D01*
Y7874D01*
G02X818898Y5000I-2874J0D01*
G01X154311D01*
G37*
G36*
G01X282349Y133350D02*
X235911D01*
X234450Y134811D01*
Y183711D01*
X200750Y217411D01*
Y373129D01*
X202711Y375090D01*
X476749D01*
X477636Y374203D01*
Y281578D01*
X477635Y281577D01*
Y280955D01*
X477636Y280954D01*
Y247911D01*
X476484Y246759D01*
X386328D01*
X384619Y245050D01*
X290489D01*
X284150Y238711D01*
Y135151D01*
X282349Y133350D01*
G37*
G36*
G01X349111Y119750D02*
X335511Y133350D01*
X287355D01*
Y133446D01*
X285650Y135151D01*
Y238089D01*
X291111Y243550D01*
X385241D01*
X386950Y245259D01*
X477106D01*
X479136Y247289D01*
Y303475D01*
X480111Y304450D01*
X494491D01*
G02X494838Y303851I0J-400D01*
G03X496062Y301738I1225J-701D01*
G01X500000D01*
G03X501225Y303851I0J1412D01*
G02X501572Y304450I347J199D01*
G01X553983D01*
X558668Y299765D01*
Y186111D01*
X562521Y182258D01*
Y121401D01*
X560870Y119750D01*
X349111D01*
G37*
G36*
G01X614909Y105250D02*
X609793Y110366D01*
Y288280D01*
X622163Y300650D01*
X679511D01*
X682360Y303499D01*
Y376753D01*
G03Y379647I-1660J1447D01*
G01Y384121D01*
X682372Y384154D01*
G03Y385646I-2072J746D01*
G01X682360Y385679D01*
Y395341D01*
X683647Y396628D01*
X731589D01*
X732875Y395342D01*
Y361364D01*
X734250Y359989D01*
Y318034D01*
X648750Y232534D01*
Y163987D01*
X651087Y161650D01*
X667889D01*
X670650Y158889D01*
Y137141D01*
G03Y137138I750J-2D01*
G03X670898Y136541I850J3D01*
G01X673950Y133489D01*
Y124618D01*
G02X673479Y124224I-400J0D01*
G03X672002Y123532I-250J-1389D01*
G02X671306I-348J198D01*
G03X668667Y122834I-1227J-697D01*
G01Y119686D01*
X668666D01*
G03X671305Y118988I1412J-1D01*
G02X672001I348J-198D01*
G03X673479Y118296I1227J697D01*
G02X673950Y117902I71J-394D01*
G01Y106611D01*
X672589Y105250D01*
X614909D01*
G37*
G36*
G01X734375Y361986D02*
Y480570D01*
X735555Y481750D01*
X820431D01*
X821772Y480409D01*
Y104620D01*
X820502Y103350D01*
X700411D01*
X698511Y105250D01*
X676863D01*
X675450Y106663D01*
Y134111D01*
X672150Y137411D01*
Y159511D01*
X668511Y163150D01*
X651709D01*
X650250Y164609D01*
Y231912D01*
X735750Y317412D01*
Y360611D01*
X734375Y361986D01*
G37*
G36*
G01X662550Y562764D02*
G03X665151Y565453I0J2602D01*
G02X665550Y565866I400J13D01*
G01X818898D01*
G02X821772Y562992I0J-2874D01*
G01Y484591D01*
X820431Y483250D01*
X801299D01*
G02X801166Y484027I0J400D01*
G03X807088Y486754I-11797J33413D01*
G01Y548128D01*
G03X777574Y484027I-17718J-30687D01*
G02X777441Y483250I-133J-377D01*
G01X734933D01*
X732875Y481192D01*
Y399414D01*
X731589Y398128D01*
X683647D01*
X662150Y419625D01*
Y562364D01*
G02X662550Y562764I400J0D01*
G37*
%LPD*%
G75*
G36*
G01X418244Y453186D02*
G02X414434Y451144I-1905J-1021D01*
G01X411481Y456655D01*
G02X415291Y458698I1905J1022D01*
G01X418244Y453186D01*
G37*
G36*
G01X409385D02*
G02X405575Y451144I-1905J-1021D01*
G01X402621Y456658D01*
X402601Y456698D01*
G02X406433Y458698I1927J979D01*
G01X409385Y453186D01*
G37*
G36*
G01X418244Y438226D02*
G02X414434Y436184I-1905J-1021D01*
G01X411481Y441695D01*
G02X415291Y443738I1905J1022D01*
G01X418244Y438226D01*
G37*
G36*
G01X409385D02*
G02X405575Y436184I-1905J-1021D01*
G01X402621Y441698D01*
X402601Y441738D01*
G02X406433Y443738I1927J979D01*
G01X409385Y438226D01*
G37*
G36*
G01X19684Y548128D02*
G02Y486754I17717J-30687D01*
G01Y548128D01*
G37*
G36*
G01X414195Y422057D02*
X414192Y422098D01*
X412076Y426048D01*
X412044Y426074D01*
G02X415530Y427943I1342J1682D01*
G01X415533Y427902D01*
X417650Y423951D01*
X417682Y423925D01*
G02X414195Y422057I-1343J-1681D01*
G37*
G36*
G01X406672Y427942D02*
X406676Y427901D01*
X408791Y423951D01*
X408823Y423926D01*
G02X405336Y422058I-1343J-1682D01*
G01X405332Y422099D01*
X403218Y426048D01*
X403186Y426074D01*
G02X406672Y427942I1342J1682D01*
G37*
G36*
G01X414195Y407097D02*
X414192Y407138D01*
X412075Y411088D01*
X412043Y411113D01*
G02X415530Y412982I1343J1682D01*
G01X415533Y412941D01*
X417650Y408991D01*
X417682Y408965D01*
G02X414195Y407097I-1343J-1681D01*
G37*
G36*
G01X406672Y412981D02*
X406676Y412940D01*
X408791Y408991D01*
X408823Y408966D01*
G02X405336Y407098I-1343J-1682D01*
G01X405332Y407139D01*
X403218Y411087D01*
X403186Y411113D01*
G02X406672Y412981I1342J1682D01*
G37*
G36*
G01X703902Y91010D02*
G02X700880I-1511J0D01*
G01Y94511D01*
G02X703902Y94510I1511J-1D01*
G01Y91010D01*
G37*
G36*
G01X711890Y92899D02*
G02X708866I-1512J0D01*
G01Y96400D01*
G02X711890Y96399I1512J-1D01*
G01Y92899D01*
G37*
G36*
G01X710872Y29134D02*
G02X706450I-2211J0D01*
G01Y34647D01*
G02X710872Y34646I2211J-1D01*
G01Y29134D01*
G37*
G36*
G01X760478Y10237D02*
G02X756056I-2211J0D01*
G01Y15749D01*
G02X760478Y15748I2211J-1D01*
G01Y10237D01*
G37*
G36*
G01X753392Y14961D02*
G02X748970I-2211J0D01*
G01Y20474D01*
G02X753392Y20473I2211J-1D01*
G01Y14961D01*
G37*
G36*
G01X746306Y10237D02*
G02X741882I-2212J0D01*
G01Y15749D01*
G02X746306Y15748I2212J-1D01*
G01Y10237D01*
G37*
G36*
G01X739218Y14961D02*
G02X734796I-2211J0D01*
G01Y20474D01*
G02X739218Y20473I2211J-1D01*
G01Y14961D01*
G37*
G36*
G01X732132Y10237D02*
G02X727710I-2211J0D01*
G01Y15749D01*
G02X732132Y15748I2211J-1D01*
G01Y10237D01*
G37*
G36*
G01X725046Y14961D02*
G02X720622I-2212J0D01*
G01Y20474D01*
G02X725046Y20473I2212J-1D01*
G01Y14961D01*
G37*
G36*
G01X717960Y10237D02*
G02X713536I-2212J0D01*
G01Y15749D01*
G02X717960Y15748I2212J-1D01*
G01Y10237D01*
G37*
G36*
G01X710872Y14961D02*
G02X706450I-2211J0D01*
G01Y20474D01*
G02X710872Y20473I2211J-1D01*
G01Y14961D01*
G37*
G36*
G01X732132Y38583D02*
G02X727710I-2211J0D01*
G01Y44096D01*
G02X732132Y44095I2211J-1D01*
G01Y38583D01*
G37*
G36*
G01X739218Y43307D02*
G02X734796I-2211J0D01*
G01Y48820D01*
G02X739218Y48819I2211J-1D01*
G01Y43307D01*
G37*
G36*
G01X746306Y38583D02*
G02X741882I-2212J0D01*
G01Y44096D01*
G02X746306Y44095I2212J-1D01*
G01Y38583D01*
G37*
G36*
G01X760478D02*
G02X756056I-2211J0D01*
G01Y44096D01*
G02X760478Y44095I2211J-1D01*
G01Y38583D01*
G37*
G36*
G01X725046Y43307D02*
G02X720622I-2212J0D01*
G01Y48820D01*
G02X725046Y48819I2212J-1D01*
G01Y43307D01*
G37*
G36*
G01X717960Y38583D02*
G02X713536I-2212J0D01*
G01Y44096D01*
G02X717960Y44095I2212J-1D01*
G01Y38583D01*
G37*
G36*
G01X753392Y43307D02*
G02X748970I-2211J0D01*
G01Y48820D01*
G02X753392Y48819I2211J-1D01*
G01Y43307D01*
G37*
G36*
G01X710872D02*
G02X706450I-2211J0D01*
G01Y48820D01*
G02X710872Y48819I2211J-1D01*
G01Y43307D01*
G37*
G36*
G01X655548Y91208D02*
G02X652526I-1511J0D01*
G01Y94709D01*
G02X655548Y94708I1511J-1D01*
G01Y91208D01*
G37*
G36*
G01X663558Y91039D02*
G02X660536I-1511J0D01*
G01Y94540D01*
G02X663558Y94539I1511J-1D01*
G01Y91039D01*
G37*
G36*
G01X671658Y91005D02*
G02X668634I-1512J0D01*
G01Y94506D01*
G02X671658Y94505I1512J-1D01*
G01Y91005D01*
G37*
G36*
G01X679736Y90996D02*
G02X676714I-1511J0D01*
G01Y94497D01*
G02X679736Y94496I1511J-1D01*
G01Y90996D01*
G37*
G36*
G01X687790Y90994D02*
G02X684768I-1511J0D01*
G01Y94495D01*
G02X687790Y94494I1511J-1D01*
G01Y90994D01*
G37*
G36*
G01X695876Y90958D02*
G02X692854I-1511J0D01*
G01Y94459D01*
G02X695876Y94458I1511J-1D01*
G01Y90958D01*
G37*
G36*
G01X578187Y186887D02*
G02X581711Y187635I1762J374D01*
G01X582637Y183274D01*
X582638Y183272D01*
G02X579123Y182485I-1753J-413D01*
G01X578187Y186887D01*
G37*
G36*
G01X582312Y202511D02*
G02X585836Y203259I1762J374D01*
G01X586762Y198898D01*
X586763Y198896D01*
G02X583248Y198109I-1753J-413D01*
G01X582312Y202511D01*
G37*
G36*
G01X589961Y218883D02*
X590897Y214481D01*
G02X587373Y213733I-1762J-374D01*
G01X586447Y218094D01*
X586446Y218096D01*
G02X589961Y218883I1753J413D01*
G37*
G36*
G01X574170Y131409D02*
G02X577694Y132157I1762J374D01*
G01X578620Y127796D01*
X578621Y127794D01*
G02X575106Y127007I-1753J-413D01*
G01X574170Y131409D01*
G37*
G36*
G01X585372Y142248D02*
G02X588896Y142996I1762J374D01*
G01X589822Y138635D01*
X589823Y138633D01*
G02X586308Y137846I-1753J-413D01*
G01X585372Y142248D01*
G37*
G36*
G01X592704Y153607D02*
G02X596228Y154355I1762J374D01*
G01X597154Y149994D01*
X597155Y149992D01*
G02X593640Y149205I-1753J-413D01*
G01X592704Y153607D01*
G37*
G36*
G01X583383Y162435D02*
G02X586907Y163183I1762J374D01*
G01X587833Y158822D01*
X587834Y158820D01*
G02X584319Y158033I-1753J-413D01*
G01X583383Y162435D01*
G37*
G36*
G01X587008Y178059D02*
G02X590532Y178807I1762J374D01*
G01X591458Y174446D01*
X591459Y174444D01*
G02X587944Y173657I-1753J-413D01*
G01X587008Y178059D01*
G37*
G36*
G01X588826Y10237D02*
G02X584402I-2212J0D01*
G01Y15749D01*
G02X588826Y15748I2212J-1D01*
G01Y10237D01*
G37*
G36*
G01X581740Y14961D02*
G02X577316I-2212J0D01*
G01Y20474D01*
G02X581740Y20473I2212J-1D01*
G01Y14961D01*
G37*
G36*
G01Y43307D02*
G02X577316I-2212J0D01*
G01Y48820D01*
G02X581740Y48819I2212J-1D01*
G01Y43307D01*
G37*
G36*
G01X588826Y38583D02*
G02X584402I-2212J0D01*
G01Y44096D01*
G02X588826Y44095I2212J-1D01*
G01Y38583D01*
G37*
G36*
G01X545043Y310269D02*
X545157Y310282D01*
X549721D01*
X549722Y310281D01*
X549798Y310278D01*
G02X549899Y307273I-76J-1507D01*
G01X549785Y307260D01*
X545157D01*
X545043Y307273D01*
G02Y310269I178J1498D01*
G37*
G36*
G01X545100Y317236D02*
X545214Y317250D01*
X549842D01*
X549956Y317236D01*
G02Y314240I-178J-1498D01*
G01X549842Y314226D01*
X545278D01*
X545277Y314228D01*
X545201Y314231D01*
G02X545100Y317236I76J1507D01*
G37*
G36*
G01X546449Y325547D02*
X546563Y325560D01*
X551191D01*
X551305Y325547D01*
G02Y322551I-178J-1498D01*
G01X551191Y322538D01*
X546627D01*
X546626Y322539D01*
X546550Y322542D01*
G02X546449Y325547I76J1507D01*
G37*
G36*
G01X574652Y10237D02*
G02X570230I-2211J0D01*
G01Y15749D01*
G02X574652Y15748I2211J-1D01*
G01Y10237D01*
G37*
G36*
G01X567566Y14961D02*
G02X563144I-2211J0D01*
G01Y20474D01*
G02X567566Y20473I2211J-1D01*
G01Y14961D01*
G37*
G36*
G01X560480Y10237D02*
G02X556056I-2212J0D01*
G01Y15749D01*
G02X560480Y15748I2212J-1D01*
G01Y10237D01*
G37*
G36*
G01X553392Y14961D02*
G02X548970I-2211J0D01*
G01Y20474D01*
G02X553392Y20473I2211J-1D01*
G01Y14961D01*
G37*
G36*
G01X546306Y10237D02*
G02X541884I-2211J0D01*
G01Y15749D01*
G02X546306Y15748I2211J-1D01*
G01Y10237D01*
G37*
G36*
G01X539220Y14961D02*
G02X534796I-2212J0D01*
G01Y20474D01*
G02X539220Y20473I2212J-1D01*
G01Y14961D01*
G37*
G36*
G01X532134Y10237D02*
G02X527710I-2212J0D01*
G01Y15749D01*
G02X532134Y15748I2212J-1D01*
G01Y10237D01*
G37*
G36*
G01X525046Y14961D02*
G02X520624I-2211J0D01*
G01Y20474D01*
G02X525046Y20473I2211J-1D01*
G01Y14961D01*
G37*
G36*
G01X517960Y10237D02*
G02X513536I-2212J0D01*
G01Y15749D01*
G02X517960Y15748I2212J-1D01*
G01Y10237D01*
G37*
G36*
G01Y38583D02*
G02X513536I-2212J0D01*
G01Y44096D01*
G02X517960Y44095I2212J-1D01*
G01Y38583D01*
G37*
G36*
G01X525046Y43307D02*
G02X520624I-2211J0D01*
G01Y48820D01*
G02X525046Y48819I2211J-1D01*
G01Y43307D01*
G37*
G36*
G01X532134Y38583D02*
G02X527710I-2212J0D01*
G01Y44096D01*
G02X532134Y44095I2212J-1D01*
G01Y38583D01*
G37*
G36*
G01X539220Y43307D02*
G02X534796I-2212J0D01*
G01Y48820D01*
G02X539220Y48819I2212J-1D01*
G01Y43307D01*
G37*
G36*
G01X546306Y38583D02*
G02X541884I-2211J0D01*
G01Y44096D01*
G02X546306Y44095I2211J-1D01*
G01Y38583D01*
G37*
G36*
G01X553392Y43307D02*
G02X548970I-2211J0D01*
G01Y48820D01*
G02X553392Y48819I2211J-1D01*
G01Y43307D01*
G37*
G36*
G01X560480Y38583D02*
G02X556056I-2212J0D01*
G01Y44096D01*
G02X560480Y44095I2212J-1D01*
G01Y38583D01*
G37*
G36*
G01X567566Y43307D02*
G02X563144I-2211J0D01*
G01Y48820D01*
G02X567566Y48819I2211J-1D01*
G01Y43307D01*
G37*
G36*
G01X574652Y38583D02*
G02X570230I-2211J0D01*
G01Y44096D01*
G02X574652Y44095I2211J-1D01*
G01Y38583D01*
G37*
G36*
G01X510874Y14961D02*
G02X506450I-2212J0D01*
G01Y20474D01*
G02X510874Y20473I2212J-1D01*
G01Y14961D01*
G37*
G36*
G01X503786Y10237D02*
G02X499364I-2211J0D01*
G01Y15749D01*
G02X503786Y15748I2211J-1D01*
G01Y10237D01*
G37*
G36*
G01X496700Y14961D02*
G02X492278I-2211J0D01*
G01Y20474D01*
G02X496700Y20473I2211J-1D01*
G01Y14961D01*
G37*
G36*
G01X489614Y10237D02*
G02X485190I-2212J0D01*
G01Y15749D01*
G02X489614Y15748I2212J-1D01*
G01Y10237D01*
G37*
G36*
G01X482526Y14961D02*
G02X478104I-2211J0D01*
G01Y20474D01*
G02X482526Y20473I2211J-1D01*
G01Y14961D01*
G37*
G36*
G01X475440Y10237D02*
G02X471018I-2211J0D01*
G01Y15749D01*
G02X475440Y15748I2211J-1D01*
G01Y10237D01*
G37*
G36*
G01X468354Y14961D02*
G02X463930I-2212J0D01*
G01Y20474D01*
G02X468354Y20473I2212J-1D01*
G01Y14961D01*
G37*
G36*
G01X461266Y10237D02*
G02X456844I-2211J0D01*
G01Y15749D01*
G02X461266Y15748I2211J-1D01*
G01Y10237D01*
G37*
G36*
G01X454180Y14961D02*
G02X449758I-2211J0D01*
G01Y20474D01*
G02X454180Y20473I2211J-1D01*
G01Y14961D01*
G37*
G36*
G01Y43307D02*
G02X449758I-2211J0D01*
G01Y48820D01*
G02X454180Y48819I2211J-1D01*
G01Y43307D01*
G37*
G36*
G01X461266Y38583D02*
G02X456844I-2211J0D01*
G01Y44096D01*
G02X461266Y44095I2211J-1D01*
G01Y38583D01*
G37*
G36*
G01X468354Y43307D02*
G02X463930I-2212J0D01*
G01Y48820D01*
G02X468354Y48819I2212J-1D01*
G01Y43307D01*
G37*
G36*
G01X475440Y38583D02*
G02X471018I-2211J0D01*
G01Y44096D01*
G02X475440Y44095I2211J-1D01*
G01Y38583D01*
G37*
G36*
G01X482526Y43307D02*
G02X478104I-2211J0D01*
G01Y48820D01*
G02X482526Y48819I2211J-1D01*
G01Y43307D01*
G37*
G36*
G01X489614Y38583D02*
G02X485190I-2212J0D01*
G01Y44096D01*
G02X489614Y44095I2212J-1D01*
G01Y38583D01*
G37*
G36*
G01X496700Y43307D02*
G02X492278I-2211J0D01*
G01Y48820D01*
G02X496700Y48819I2211J-1D01*
G01Y43307D01*
G37*
G36*
G01X503786Y38583D02*
G02X499364I-2211J0D01*
G01Y44096D01*
G02X503786Y44095I2211J-1D01*
G01Y38583D01*
G37*
G36*
G01X510874Y43307D02*
G02X506450I-2212J0D01*
G01Y48820D01*
G02X510874Y48819I2212J-1D01*
G01Y43307D01*
G37*
G36*
G01X447094Y10237D02*
G02X442670I-2212J0D01*
G01Y15749D01*
G02X447094Y15748I2212J-1D01*
G01Y10237D01*
G37*
G36*
G01X440008Y14961D02*
G02X435584I-2212J0D01*
G01Y20474D01*
G02X440008Y20473I2212J-1D01*
G01Y14961D01*
G37*
G36*
G01X432920Y10237D02*
G02X428498I-2211J0D01*
G01Y15749D01*
G02X432920Y15748I2211J-1D01*
G01Y10237D01*
G37*
G36*
G01X425834Y14961D02*
G02X421410I-2212J0D01*
G01Y20474D01*
G02X425834Y20473I2212J-1D01*
G01Y14961D01*
G37*
G36*
G01X418748Y10237D02*
G02X414324I-2212J0D01*
G01Y15749D01*
G02X418748Y15748I2212J-1D01*
G01Y10237D01*
G37*
G36*
G01X411660Y14961D02*
G02X407238I-2211J0D01*
G01Y20474D01*
G02X411660Y20473I2211J-1D01*
G01Y14961D01*
G37*
G36*
G01X404574Y10237D02*
G02X400152I-2211J0D01*
G01Y15749D01*
G02X404574Y15748I2211J-1D01*
G01Y10237D01*
G37*
G36*
G01X397488Y14961D02*
G02X393064I-2212J0D01*
G01Y20474D01*
G02X397488Y20473I2212J-1D01*
G01Y14961D01*
G37*
G36*
G01Y43307D02*
G02X393064I-2212J0D01*
G01Y48820D01*
G02X397488Y48819I2212J-1D01*
G01Y43307D01*
G37*
G36*
G01X404574Y38583D02*
G02X400152I-2211J0D01*
G01Y44096D01*
G02X404574Y44095I2211J-1D01*
G01Y38583D01*
G37*
G36*
G01X411660Y43307D02*
G02X407238I-2211J0D01*
G01Y48820D01*
G02X411660Y48819I2211J-1D01*
G01Y43307D01*
G37*
G36*
G01X418748Y38583D02*
G02X414324I-2212J0D01*
G01Y44096D01*
G02X418748Y44095I2212J-1D01*
G01Y38583D01*
G37*
G36*
G01X425834Y43307D02*
G02X421410I-2212J0D01*
G01Y48820D01*
G02X425834Y48819I2212J-1D01*
G01Y43307D01*
G37*
G36*
G01X432920Y38583D02*
G02X428498I-2211J0D01*
G01Y44096D01*
G02X432920Y44095I2211J-1D01*
G01Y38583D01*
G37*
G36*
G01X440008Y43307D02*
G02X435584I-2212J0D01*
G01Y48820D01*
G02X440008Y48819I2212J-1D01*
G01Y43307D01*
G37*
G36*
G01X447094Y38583D02*
G02X442670I-2212J0D01*
G01Y44096D01*
G02X447094Y44095I2212J-1D01*
G01Y38583D01*
G37*
G36*
G01X390400Y10237D02*
G02X385978I-2211J0D01*
G01Y15749D01*
G02X390400Y15748I2211J-1D01*
G01Y10237D01*
G37*
G36*
G01X383314Y14961D02*
G02X378892I-2211J0D01*
G01Y20474D01*
G02X383314Y20473I2211J-1D01*
G01Y14961D01*
G37*
G36*
G01X376228Y10237D02*
G02X371804I-2212J0D01*
G01Y15749D01*
G02X376228Y15748I2212J-1D01*
G01Y10237D01*
G37*
G36*
G01X369140Y14961D02*
G02X364718I-2211J0D01*
G01Y20474D01*
G02X369140Y20473I2211J-1D01*
G01Y14961D01*
G37*
G36*
G01X362054Y10237D02*
G02X357632I-2211J0D01*
G01Y15749D01*
G02X362054Y15748I2211J-1D01*
G01Y10237D01*
G37*
G36*
G01X354968Y14961D02*
G02X350544I-2212J0D01*
G01Y20474D01*
G02X354968Y20473I2212J-1D01*
G01Y14961D01*
G37*
G36*
G01X347882Y10237D02*
G02X343458I-2212J0D01*
G01Y15749D01*
G02X347882Y15748I2212J-1D01*
G01Y10237D01*
G37*
G36*
G01X340794Y14961D02*
G02X336372I-2211J0D01*
G01Y20474D01*
G02X340794Y20473I2211J-1D01*
G01Y14961D01*
G37*
G36*
G01Y43307D02*
G02X336372I-2211J0D01*
G01Y48820D01*
G02X340794Y48819I2211J-1D01*
G01Y43307D01*
G37*
G36*
G01X347882Y38583D02*
G02X343458I-2212J0D01*
G01Y44096D01*
G02X347882Y44095I2212J-1D01*
G01Y38583D01*
G37*
G36*
G01X354968Y43307D02*
G02X350544I-2212J0D01*
G01Y48820D01*
G02X354968Y48819I2212J-1D01*
G01Y43307D01*
G37*
G36*
G01X362054Y38583D02*
G02X357632I-2211J0D01*
G01Y44096D01*
G02X362054Y44095I2211J-1D01*
G01Y38583D01*
G37*
G36*
G01X369140Y43307D02*
G02X364718I-2211J0D01*
G01Y48820D01*
G02X369140Y48819I2211J-1D01*
G01Y43307D01*
G37*
G36*
G01X376228Y38583D02*
G02X371804I-2212J0D01*
G01Y44096D01*
G02X376228Y44095I2212J-1D01*
G01Y38583D01*
G37*
G36*
G01X383314Y43307D02*
G02X378892I-2211J0D01*
G01Y48820D01*
G02X383314Y48819I2211J-1D01*
G01Y43307D01*
G37*
G36*
G01X390400Y38583D02*
G02X385978I-2211J0D01*
G01Y44096D01*
G02X390400Y44095I2211J-1D01*
G01Y38583D01*
G37*
G36*
G01X545015Y302778D02*
X545129Y302792D01*
X549757D01*
X549871Y302778D01*
G02Y299782I-178J-1498D01*
G01X549757Y299768D01*
X545193D01*
X545192Y299770D01*
X545116Y299773D01*
G02X545015Y302778I76J1507D01*
G37*
G36*
G01X547365Y238846D02*
G02Y242430I0J1792D01*
G01X551866D01*
G02X551865Y238846I-1J-1792D01*
G01X547365D01*
G37*
G36*
G01X546475Y246418D02*
G02Y250000I0J1791D01*
G01X550976D01*
G02X550975Y246418I-1J-1791D01*
G01X546475D01*
G37*
G36*
G01X546217Y254004D02*
G02Y257588I0J1792D01*
G01X550718D01*
G02X550717Y254004I-1J-1792D01*
G01X546217D01*
G37*
G36*
G01X522354Y180373D02*
G02X518750I-1802J0D01*
G01Y184874D01*
G02X522354Y184873I1802J-1D01*
G01Y180373D01*
G37*
G36*
G01X549000Y230108D02*
G02Y233692I0J1792D01*
G01X553501D01*
G02X553500Y230108I-1J-1792D01*
G01X549000D01*
G37*
G36*
G01X515748Y261254D02*
G02Y258432I0J-1411D01*
G01X511810D01*
G02X511811Y261254I1J1411D01*
G01X515748D01*
G37*
G36*
G01X500000Y296688D02*
G02Y293864I0J-1412D01*
G01X496062D01*
G02X496063Y296688I1J1412D01*
G01X500000D01*
G37*
G36*
G01X515748Y288814D02*
G02Y285990I0J-1412D01*
G01X511810D01*
G02X511811Y288814I1J1412D01*
G01X515748D01*
G37*
G36*
G01Y273066D02*
G02Y270242I0J-1412D01*
G01X511810D01*
G02X511811Y273066I1J1412D01*
G01X515748D01*
G37*
G36*
G01X500000Y249444D02*
G02Y246620I0J-1412D01*
G01X496062D01*
G02X496063Y249444I1J1412D01*
G01X500000D01*
G37*
G36*
G01Y288814D02*
G02Y285990I0J-1412D01*
G01X496062D01*
G02X496063Y288814I1J1412D01*
G01X500000D01*
G37*
G36*
G01Y284876D02*
G02Y282054I0J-1411D01*
G01X496062D01*
G02X496063Y284876I1J1411D01*
G01X500000D01*
G37*
G36*
G01Y280940D02*
G02Y278116I0J-1412D01*
G01X496062D01*
G02X496063Y280940I1J1412D01*
G01X500000D01*
G37*
G36*
G01Y277002D02*
G02Y274180I0J-1411D01*
G01X496062D01*
G02X496063Y277002I1J1411D01*
G01X500000D01*
G37*
G36*
G01Y273066D02*
G02Y270242I0J-1412D01*
G01X496062D01*
G02X496063Y273066I1J1412D01*
G01X500000D01*
G37*
G36*
G01Y269128D02*
G02Y266306I0J-1411D01*
G01X496062D01*
G02X496063Y269128I1J1411D01*
G01X500000D01*
G37*
G36*
G01Y261254D02*
G02Y258432I0J-1411D01*
G01X496062D01*
G02X496063Y261254I1J1411D01*
G01X500000D01*
G37*
G36*
G01Y241570D02*
G02Y238746I0J-1412D01*
G01X496062D01*
G02X496063Y241570I1J1412D01*
G01X500000D01*
G37*
G36*
G01Y245506D02*
G02Y242684I0J-1411D01*
G01X496062D01*
G02X496063Y245506I1J1411D01*
G01X500000D01*
G37*
G36*
G01Y253380D02*
G02Y250558I0J-1411D01*
G01X496062D01*
G02X496063Y253380I1J1411D01*
G01X500000D01*
G37*
G36*
G01Y257318D02*
G02Y254494I0J-1412D01*
G01X496062D01*
G02X496063Y257318I1J1412D01*
G01X500000D01*
G37*
G36*
G01X511811Y284876D02*
G02Y282054I0J-1411D01*
G01X507873D01*
G02X507874Y284876I1J1411D01*
G01X511811D01*
G37*
G36*
G01X515748Y280940D02*
G02Y278116I0J-1412D01*
G01X511810D01*
G02X511811Y280940I1J1412D01*
G01X515748D01*
G37*
G36*
G01X511811Y277002D02*
G02Y274180I0J-1411D01*
G01X507873D01*
G02X507874Y277002I1J1411D01*
G01X511811D01*
G37*
G36*
G01Y269128D02*
G02Y266306I0J-1411D01*
G01X507873D01*
G02X507874Y269128I1J1411D01*
G01X511811D01*
G37*
G36*
G01Y257318D02*
G02Y254494I0J-1412D01*
G01X507873D01*
G02X507874Y257318I1J1412D01*
G01X511811D01*
G37*
G36*
G01X515748Y253380D02*
G02Y250558I0J-1411D01*
G01X511810D01*
G02X511811Y253380I1J1411D01*
G01X515748D01*
G37*
G36*
G01X511811Y249444D02*
G02Y246620I0J-1412D01*
G01X507873D01*
G02X507874Y249444I1J1412D01*
G01X511811D01*
G37*
G36*
G01X515748Y245506D02*
G02Y242684I0J-1411D01*
G01X511810D01*
G02X511811Y245506I1J1411D01*
G01X515748D01*
G37*
G36*
G01X511811Y241570D02*
G02Y238746I0J-1412D01*
G01X507873D01*
G02X507874Y241570I1J1412D01*
G01X511811D01*
G37*
G36*
G01X500000Y292750D02*
G02Y289928I0J-1411D01*
G01X496062D01*
G02X496063Y292750I1J1411D01*
G01X500000D01*
G37*
G36*
G01Y300624D02*
G02Y297802I0J-1411D01*
G01X496062D01*
G02X496063Y300624I1J1411D01*
G01X500000D01*
G37*
G36*
G01X458104Y204725D02*
G02X455282I-1411J0D01*
G01Y208663D01*
G02X458104Y208662I1411J-1D01*
G01Y204725D01*
G37*
G36*
G01X462042Y200788D02*
G02X459218I-1412J0D01*
G01Y204726D01*
G02X462042Y204725I1412J-1D01*
G01Y200788D01*
G37*
G36*
G01X465978Y204725D02*
G02X463156I-1411J0D01*
G01Y208663D01*
G02X465978Y208662I1411J-1D01*
G01Y204725D01*
G37*
G36*
G01X469916Y200788D02*
G02X467092I-1412J0D01*
G01Y204726D01*
G02X469916Y204725I1412J-1D01*
G01Y200788D01*
G37*
G36*
G01X473852Y204725D02*
G02X471030I-1411J0D01*
G01Y208663D01*
G02X473852Y208662I1411J-1D01*
G01Y204725D01*
G37*
G36*
G01X477790Y200788D02*
G02X474966I-1412J0D01*
G01Y204726D01*
G02X477790Y204725I1412J-1D01*
G01Y200788D01*
G37*
G36*
G01X481726Y204725D02*
G02X478904I-1411J0D01*
G01Y208663D01*
G02X481726Y208662I1411J-1D01*
G01Y204725D01*
G37*
G36*
G01X485664Y200788D02*
G02X482840I-1412J0D01*
G01Y204726D01*
G02X485664Y204725I1412J-1D01*
G01Y200788D01*
G37*
G36*
G01X489600Y204725D02*
G02X486778I-1411J0D01*
G01Y208663D01*
G02X489600Y208662I1411J-1D01*
G01Y204725D01*
G37*
G36*
G01X512228Y180431D02*
G02X508626I-1801J0D01*
G01Y184932D01*
G02X512228Y184931I1801J-1D01*
G01Y180431D01*
G37*
G36*
G01X502104Y180489D02*
G02X498500I-1802J0D01*
G01Y184990D01*
G02X502104Y184989I1802J-1D01*
G01Y180489D01*
G37*
G36*
G01X492678Y180547D02*
G02X489076I-1801J0D01*
G01Y185048D01*
G02X492678Y185047I1801J-1D01*
G01Y180547D01*
G37*
G36*
G01X503937Y210074D02*
G02Y207250I0J-1412D01*
G01X499999D01*
G02X500000Y210074I1J1412D01*
G01X503937D01*
G37*
G36*
G01X500000Y214010D02*
G02Y211188I0J-1411D01*
G01X496062D01*
G02X496063Y214010I1J1411D01*
G01X500000D01*
G37*
G36*
G01Y217948D02*
G02Y215124I0J-1412D01*
G01X496062D01*
G02X496063Y217948I1J1412D01*
G01X500000D01*
G37*
G36*
G01Y221884D02*
G02Y219062I0J-1411D01*
G01X496062D01*
G02X496063Y221884I1J1411D01*
G01X500000D01*
G37*
G36*
G01Y225822D02*
G02Y222998I0J-1412D01*
G01X496062D01*
G02X496063Y225822I1J1412D01*
G01X500000D01*
G37*
G36*
G01Y229758D02*
G02Y226936I0J-1411D01*
G01X496062D01*
G02X496063Y229758I1J1411D01*
G01X500000D01*
G37*
G36*
G01Y233696D02*
G02Y230872I0J-1412D01*
G01X496062D01*
G02X496063Y233696I1J1412D01*
G01X500000D01*
G37*
G36*
G01Y237632D02*
G02Y234810I0J-1411D01*
G01X496062D01*
G02X496063Y237632I1J1411D01*
G01X500000D01*
G37*
G36*
G01X489600Y216536D02*
G02X486778I-1411J0D01*
G01Y220474D01*
G02X489600Y220473I1411J-1D01*
G01Y216536D01*
G37*
G36*
G01X485664D02*
G02X482840I-1412J0D01*
G01Y220474D01*
G02X485664Y220473I1412J-1D01*
G01Y216536D01*
G37*
G36*
G01X481726D02*
G02X478904I-1411J0D01*
G01Y220474D01*
G02X481726Y220473I1411J-1D01*
G01Y216536D01*
G37*
G36*
G01X477790D02*
G02X474966I-1412J0D01*
G01Y220474D01*
G02X477790Y220473I1412J-1D01*
G01Y216536D01*
G37*
G36*
G01X473852D02*
G02X471030I-1411J0D01*
G01Y220474D01*
G02X473852Y220473I1411J-1D01*
G01Y216536D01*
G37*
G36*
G01X469916D02*
G02X467092I-1412J0D01*
G01Y220474D01*
G02X469916Y220473I1412J-1D01*
G01Y216536D01*
G37*
G36*
G01X465978D02*
G02X463156I-1411J0D01*
G01Y220474D01*
G02X465978Y220473I1411J-1D01*
G01Y216536D01*
G37*
G36*
G01X462042D02*
G02X459218I-1412J0D01*
G01Y220474D01*
G02X462042Y220473I1412J-1D01*
G01Y216536D01*
G37*
G36*
G01X458104D02*
G02X455282I-1411J0D01*
G01Y220474D01*
G02X458104Y220473I1411J-1D01*
G01Y216536D01*
G37*
G36*
G01X391176Y212599D02*
G02X388352I-1412J0D01*
G01Y216537D01*
G02X391176Y216536I1412J-1D01*
G01Y212599D01*
G37*
G36*
G01X402986Y200788D02*
G02X400164I-1411J0D01*
G01Y204726D01*
G02X402986Y204725I1411J-1D01*
G01Y200788D01*
G37*
G36*
G01X410860D02*
G02X408038I-1411J0D01*
G01Y204726D01*
G02X410860Y204725I1411J-1D01*
G01Y200788D01*
G37*
G36*
G01X418734D02*
G02X415912I-1411J0D01*
G01Y204726D01*
G02X418734Y204725I1411J-1D01*
G01Y200788D01*
G37*
G36*
G01X426608D02*
G02X423786I-1411J0D01*
G01Y204726D01*
G02X426608Y204725I1411J-1D01*
G01Y200788D01*
G37*
G36*
G01X434482D02*
G02X431660I-1411J0D01*
G01Y204726D01*
G02X434482Y204725I1411J-1D01*
G01Y200788D01*
G37*
G36*
G01X438420Y204725D02*
G02X435596I-1412J0D01*
G01Y208663D01*
G02X438420Y208662I1412J-1D01*
G01Y204725D01*
G37*
G36*
G01X442356Y200788D02*
G02X439534I-1411J0D01*
G01Y204726D01*
G02X442356Y204725I1411J-1D01*
G01Y200788D01*
G37*
G36*
G01X446294Y204725D02*
G02X443470I-1412J0D01*
G01Y208663D01*
G02X446294Y208662I1412J-1D01*
G01Y204725D01*
G37*
G36*
G01X450230Y200788D02*
G02X447408I-1411J0D01*
G01Y204726D01*
G02X450230Y204725I1411J-1D01*
G01Y200788D01*
G37*
G36*
G01Y216536D02*
G02X447408I-1411J0D01*
G01Y220474D01*
G02X450230Y220473I1411J-1D01*
G01Y216536D01*
G37*
G36*
G01X446294D02*
G02X443470I-1412J0D01*
G01Y220474D01*
G02X446294Y220473I1412J-1D01*
G01Y216536D01*
G37*
G36*
G01X442356D02*
G02X439534I-1411J0D01*
G01Y220474D01*
G02X442356Y220473I1411J-1D01*
G01Y216536D01*
G37*
G36*
G01X438420D02*
G02X435596I-1412J0D01*
G01Y220474D01*
G02X438420Y220473I1412J-1D01*
G01Y216536D01*
G37*
G36*
G01X434482D02*
G02X431660I-1411J0D01*
G01Y220474D01*
G02X434482Y220473I1411J-1D01*
G01Y216536D01*
G37*
G36*
G01X430546D02*
G02X427722I-1412J0D01*
G01Y220474D01*
G02X430546Y220473I1412J-1D01*
G01Y216536D01*
G37*
G36*
G01X426608D02*
G02X423786I-1411J0D01*
G01Y220474D01*
G02X426608Y220473I1411J-1D01*
G01Y216536D01*
G37*
G36*
G01X422672D02*
G02X419848I-1412J0D01*
G01Y220474D01*
G02X422672Y220473I1412J-1D01*
G01Y216536D01*
G37*
G36*
G01X418734D02*
G02X415912I-1411J0D01*
G01Y220474D01*
G02X418734Y220473I1411J-1D01*
G01Y216536D01*
G37*
G36*
G01X414798D02*
G02X411974I-1412J0D01*
G01Y220474D01*
G02X414798Y220473I1412J-1D01*
G01Y216536D01*
G37*
G36*
G01X410860D02*
G02X408038I-1411J0D01*
G01Y220474D01*
G02X410860Y220473I1411J-1D01*
G01Y216536D01*
G37*
G36*
G01X406924D02*
G02X404100I-1412J0D01*
G01Y220474D01*
G02X406924Y220473I1412J-1D01*
G01Y216536D01*
G37*
G36*
G01X402986D02*
G02X400164I-1411J0D01*
G01Y220474D01*
G02X402986Y220473I1411J-1D01*
G01Y216536D01*
G37*
G36*
G01X399050D02*
G02X396226I-1412J0D01*
G01Y220474D01*
G02X399050Y220473I1412J-1D01*
G01Y216536D01*
G37*
G36*
G01X430546Y204725D02*
G02X427722I-1412J0D01*
G01Y208663D01*
G02X430546Y208662I1412J-1D01*
G01Y204725D01*
G37*
G36*
G01X422672D02*
G02X419848I-1412J0D01*
G01Y208663D01*
G02X422672Y208662I1412J-1D01*
G01Y204725D01*
G37*
G36*
G01X414798D02*
G02X411974I-1412J0D01*
G01Y208663D01*
G02X414798Y208662I1412J-1D01*
G01Y204725D01*
G37*
G36*
G01X406924D02*
G02X404100I-1412J0D01*
G01Y208663D01*
G02X406924Y208662I1412J-1D01*
G01Y204725D01*
G37*
G36*
G01X399050D02*
G02X396226I-1412J0D01*
G01Y208663D01*
G02X399050Y208662I1412J-1D01*
G01Y204725D01*
G37*
G36*
G01X395112Y200788D02*
G02X392290I-1411J0D01*
G01Y204726D01*
G02X395112Y204725I1411J-1D01*
G01Y200788D01*
G37*
G36*
G01X661856Y118988D02*
G02X659217Y119686I-1227J697D01*
G01X659218D01*
Y122833D01*
G02X661857Y123532I1412J1D01*
G03X662552I347J198D01*
G02X665190Y122834I1227J-698D01*
G01Y119685D01*
G02X662552Y118988I-1411J0D01*
G03X661856I-348J-198D01*
G37*
G36*
G01X655786Y118047D02*
X657478D01*
G02X657479Y115025I1J-1511D01*
G01X654331Y115024D01*
G02X653474Y117780I0J1511D01*
G03Y118440I-227J330D01*
G02X652818Y119685I855J1246D01*
G01Y122834D01*
G02X653474Y124080I1511J0D01*
G03Y124739I-227J330D01*
G02Y127229I857J1245D01*
G03Y127888I-227J330D01*
G02X652818Y129134I855J1246D01*
G01Y132283D01*
G02X653179Y133262I1512J-1D01*
G03X652874Y133922I-305J260D01*
G01X651180D01*
G02X651181Y136944I1J1511D01*
G01X652873D01*
G03X653178Y137603I0J400D01*
G02X652818Y138582I1151J979D01*
G01Y141732D01*
G02X653179Y142711I1512J-1D01*
G03X652874Y143370I-305J259D01*
G01X651180D01*
G02X651181Y146394I1J1512D01*
G01X652873D01*
G03X653178Y147052I0J400D01*
G02X652818Y148031I1151J979D01*
G01Y151181D01*
G02X655842I1512J0D01*
G01Y148030D01*
G02X655187Y146786I-1512J1D01*
G03Y146127I227J-329D01*
G02X655186Y143637I-857J-1245D01*
G03Y142977I227J-330D01*
G02X655842Y141732I-855J-1246D01*
G01Y138581D01*
G02X655187Y137337I-1512J1D01*
G03Y136678I227J-329D01*
G02X655186Y134188I-857J-1245D01*
G03Y133528I227J-330D01*
G02X655842Y132283I-855J-1246D01*
G01Y129133D01*
G02X655481Y128155I-1512J2D01*
G03X655786Y127496I305J-259D01*
G01X657481D01*
G02X657480Y124472I-1J-1512D01*
G01X655786D01*
G03X655481Y123813I0J-400D01*
G02X655842Y122834I-1151J-980D01*
G01Y119684D01*
G02X655482Y118706I-1512J1D01*
G03X655786Y118047I305J-259D01*
G37*
G36*
G01X680754Y118988D02*
G02X678115Y119686I-1227J697D01*
G01X678116D01*
Y122834D01*
G02X680755Y123532I1412J1D01*
G03X681451I348J198D01*
G02X684090Y122834I1227J-697D01*
G01X684089D01*
Y119685D01*
X684088D01*
G02X681450Y118988I-1411J0D01*
G03X680754I-348J-198D01*
G37*
G36*
G01X690203D02*
G02X687564Y119686I-1227J697D01*
G01X687565D01*
Y122834D01*
G02X690204Y123533I1412J1D01*
G03X690899I347J198D01*
G02X693538Y122835I1227J-698D01*
G01Y119686D01*
G02X690899Y118988I-1412J0D01*
G03X690203I-348J-197D01*
G37*
G54D41*
X98425Y472441D03*
X137795D03*
G54D38*
X27058Y25484D03*
X81539Y542850D03*
X798456Y26432D03*
G54D43*
X389764Y460630D03*
X437008D03*
G54D40*
X116063Y14567D03*
G54D46*
X781496Y198819D03*
G54D42*
X295276Y531496D03*
G54D45*
X374016Y156221D03*
G54D44*
X531496Y531496D03*
G54D39*
X116066Y39074D03*
G54D12*
X22550Y156750D03*
X54697Y165269D03*
X58697D03*
X59600Y152000D03*
X52400Y237800D03*
X28455Y187767D03*
X28749Y191548D03*
X39301Y203166D03*
X33700Y230600D03*
X21910Y217500D03*
X22250Y223500D03*
X39416Y206616D03*
X65500Y237800D03*
X70500D03*
X75500D03*
X23800Y211200D03*
X27500D03*
X59700Y178600D03*
X68400Y177950D03*
X76800Y178200D03*
X46194Y179835D03*
X50194D03*
X39320Y213823D03*
X64000Y178400D03*
X72800Y178200D03*
X33759Y274180D03*
X37830D03*
X23100Y292200D03*
Y287700D03*
X56026Y256117D03*
X23100Y283200D03*
X22750Y275450D03*
X23500Y296700D03*
X68300Y292200D03*
X45650Y250280D03*
X49320D03*
X40290Y239814D03*
X35405Y239808D03*
X32469Y250280D03*
X37469D03*
X69143Y334598D03*
X47443Y334198D03*
X27947Y334066D03*
X37049Y302949D03*
X23100Y318500D03*
Y314000D03*
X52450Y333850D03*
X31450Y334050D03*
X74150Y334250D03*
X28000Y326500D03*
X24000Y301750D03*
X23400Y309500D03*
X67800Y318000D03*
X67700Y321500D03*
X58900Y334180D03*
X62325Y334068D03*
X37900Y334380D03*
X41325Y334268D03*
X57350Y387800D03*
X46900Y378233D03*
X26100Y378352D03*
X69300Y378800D03*
X31240Y393440D03*
X49700Y391000D03*
X54040Y399390D03*
X65500Y378800D03*
X43000Y378233D03*
X22000Y378352D03*
X53500Y403150D03*
X49700Y402000D03*
X50700Y378233D03*
X54800Y373600D03*
X29900Y378252D03*
X38200Y373800D03*
X34100D03*
X73100Y378700D03*
X60400Y373600D03*
X77200Y374000D03*
X65375Y392835D03*
X35800Y363400D03*
X40100D03*
X92300Y199400D03*
Y209400D03*
Y204400D03*
X90800Y217900D03*
X82600Y232000D03*
X78850Y221000D03*
X87300Y230650D03*
X92300Y190900D03*
X81300Y178050D03*
X85700Y178000D03*
X92300Y194900D03*
X78800Y205900D03*
X92300Y213900D03*
X89800Y178000D03*
X81000Y291700D03*
X80896Y286695D03*
X80688Y281695D03*
Y276695D03*
X93884Y242333D03*
X90238Y334391D03*
X78600Y321700D03*
X78700Y317400D03*
X102300Y329100D03*
X95245Y334043D03*
X80700Y309400D03*
X80600Y304600D03*
Y334580D03*
X84025Y334468D03*
X102400Y333900D03*
X106500D03*
X89895Y378426D03*
X83232Y399956D03*
X85795Y378426D03*
X102395Y373793D03*
X93695Y378426D03*
X81300Y374000D03*
X98295Y373793D03*
X106709Y383400D03*
X112023Y383013D03*
X78171Y363195D03*
X82171D03*
X99266Y362988D03*
X103266D03*
X104900Y412200D03*
X102679Y391150D03*
X112638Y391197D03*
X107582Y391266D03*
X102850Y452650D03*
X94488Y489888D03*
X182100Y105500D03*
X155991Y110061D03*
X200550Y111350D03*
X152800Y113400D03*
X164020Y101127D03*
X158612Y126645D03*
X198202Y135298D03*
X201139Y121630D03*
X172800Y141001D03*
X180300Y175400D03*
X145585Y132451D03*
X197100Y298800D03*
X162522Y331774D03*
X196600Y306800D03*
X250137Y36053D03*
X261499Y55353D03*
X257499D03*
X241750Y98250D03*
X238867Y63650D03*
X255300Y72600D03*
X234693Y57400D03*
X255154Y69177D03*
X233759Y64752D03*
X220228Y63651D03*
X245800Y279200D03*
X207600Y292400D03*
X204400Y288700D03*
X248900Y282932D03*
X259629Y281000D03*
X242351Y282900D03*
X228300Y280900D03*
X219400Y279400D03*
X262800Y277835D03*
X242400Y289700D03*
X242402Y286300D03*
X225500Y278900D03*
X222320Y277658D03*
X207500Y278400D03*
X204997Y280702D03*
X253575Y320167D03*
X235500Y320100D03*
X218500Y320200D03*
X222000Y310600D03*
X231700Y320100D03*
X249775Y320167D03*
X214700Y320200D03*
X212198Y328316D03*
X208648Y328452D03*
X261365Y324351D03*
X245943Y326300D03*
X246100Y329700D03*
X230400Y326200D03*
Y329600D03*
X253245Y329698D03*
X253154Y326227D03*
X241556Y340111D03*
X237483Y339988D03*
X230000Y336500D03*
X233400Y336600D03*
X218400Y326600D03*
X218300Y330000D03*
X230400Y348000D03*
X255500Y423361D03*
X237600Y390500D03*
X261581Y370979D03*
X256172Y409530D03*
X261996Y365663D03*
X263250Y423411D03*
X257996Y365663D03*
X259800Y423400D03*
X256900Y380900D03*
X281700Y52285D03*
X285500D03*
X308591Y68928D03*
X304591D03*
X308591Y73074D03*
X311182Y58692D03*
X276700Y66700D03*
X283385Y100227D03*
X287385D03*
X319533Y114283D03*
X291385Y100227D03*
X295385D03*
X306196Y110209D03*
X310711Y113820D03*
X314772Y108292D03*
X300311Y60800D03*
X300385Y108227D03*
X311182Y62800D03*
X272937Y90362D03*
X266895Y100227D03*
X306280Y82574D03*
X283393Y92325D03*
X301280Y82574D03*
X272937Y85862D03*
X304591Y73074D03*
X318773Y108083D03*
X278039Y82185D03*
X279385Y100227D03*
X292030Y90574D03*
X292385Y108227D03*
X280298Y95556D03*
X296280Y82574D03*
X324026Y115936D03*
X321343Y122343D03*
X321051Y134028D03*
X304529Y118792D03*
X317700Y275400D03*
X270143Y276969D03*
X323681Y259023D03*
X319881D03*
X284498Y299976D03*
X299635Y292650D03*
X317600Y278800D03*
X319543Y290159D03*
X303032Y289900D03*
X268400Y281000D03*
X266406Y277835D03*
X306292Y252825D03*
X302262Y262642D03*
X299635Y288650D03*
X292225Y288267D03*
X297021Y346579D03*
X287350Y351200D03*
X319550Y347169D03*
X305147Y354706D03*
X316050Y342200D03*
X287350Y357700D03*
X322500Y353700D03*
X301500Y337500D03*
X320650Y336456D03*
X306060Y337640D03*
X310200Y337600D03*
X294250Y325000D03*
X277150Y332000D03*
X273165Y320351D03*
X280800Y325000D03*
X290750D03*
X280217Y350927D03*
X269365Y320351D03*
X325500Y325400D03*
X314241Y308459D03*
X314300Y311900D03*
X308180Y305200D03*
X305628Y320511D03*
X301628D03*
X325500Y321400D03*
X314400Y327851D03*
X314045Y302900D03*
X314500Y324251D03*
X319100Y330600D03*
X305628Y324511D03*
X324100Y307814D03*
X265365Y324351D03*
X281150Y332000D03*
X288536Y314764D03*
X275696Y314340D03*
X308398Y386479D03*
X304205Y382450D03*
X304398Y386479D03*
X292800Y363800D03*
X300019Y379524D03*
X296079D03*
X325200Y365100D03*
X312398Y386479D03*
X266300Y412100D03*
X270618Y385867D03*
X268004Y424361D03*
X323448Y405064D03*
X266500Y364000D03*
X325651Y439668D03*
X325629Y443510D03*
X328600Y114400D03*
X328711Y108053D03*
X335722Y94574D03*
X329722D03*
X374616Y172378D03*
X370061Y172433D03*
X355500Y144500D03*
X342000Y141600D03*
X331649Y126111D03*
X339049Y124238D03*
X335994Y126119D03*
X341913Y145049D03*
X374915Y176442D03*
X359969Y124510D03*
X349911Y136954D03*
X341757Y211056D03*
X337157Y206052D03*
X335701Y223995D03*
X352047Y220590D03*
X357546Y230354D03*
X360710Y231897D03*
X376306Y182715D03*
X351723Y178499D03*
X354143Y183439D03*
X362260Y184360D03*
X364169Y188366D03*
X366460Y191794D03*
X368558Y194540D03*
X379415Y194608D03*
X370570Y198219D03*
X371124Y178760D03*
X372517Y182362D03*
X380400Y287400D03*
X382000Y296500D03*
X384600Y285600D03*
X368714Y261134D03*
X339500Y260400D03*
X327868Y290125D03*
X365996Y287265D03*
Y272841D03*
X366169Y246591D03*
X370669D03*
X338650Y281350D03*
X361996Y272841D03*
X379000Y272600D03*
X384300Y291100D03*
X346900Y281300D03*
X343100D03*
X357996Y272841D03*
X328134Y252720D03*
X332000Y266336D03*
X376633Y261543D03*
X340280Y253765D03*
X337500Y266050D03*
X358096Y262268D03*
X341998Y256700D03*
X368610Y257299D03*
X376633Y256851D03*
X385887Y305222D03*
X381396Y302610D03*
X335400Y337400D03*
X345700Y349773D03*
X337600Y349600D03*
X339000Y344700D03*
X330000Y345800D03*
X335882Y309823D03*
X327400Y342600D03*
X386159Y337080D03*
X368050Y337200D03*
X370250Y347600D03*
X379148Y337184D03*
X384341Y315377D03*
X377324Y302844D03*
X360050Y337200D03*
X348600Y323900D03*
X359400Y347200D03*
X375148Y337184D03*
X382600Y337200D03*
X344000Y316000D03*
X346500Y302500D03*
X356550Y337200D03*
X348596Y337250D03*
X347750Y315850D03*
X352396Y337200D03*
X331026Y303354D03*
X328100Y331300D03*
X329364Y316949D03*
X364050Y337200D03*
X374250Y347600D03*
X359200Y315800D03*
X355200D03*
X360300Y323900D03*
X363400Y315800D03*
X344000Y388500D03*
X340375Y365944D03*
X331765Y386535D03*
X367450Y409955D03*
X338000Y421000D03*
X367350Y406455D03*
X360000Y410000D03*
X337592Y405027D03*
X327365Y433732D03*
X337900Y431200D03*
X448300Y337500D03*
X444100Y341000D03*
X444200Y337600D03*
X444100Y345000D03*
X440300Y337500D03*
X444959Y352053D03*
X389559Y337103D03*
X421500Y337500D03*
X427500D03*
X448431Y348737D03*
X416822Y347133D03*
X412381Y347149D03*
X435000Y347800D03*
X441000D03*
X433500Y337500D03*
X426464Y347078D03*
X397000Y337000D03*
X401700Y337350D03*
X392959Y337099D03*
X405921Y347159D03*
X430464Y347078D03*
X390550Y326820D03*
X405783Y339318D03*
X448500Y424000D03*
X445000Y422000D03*
X452300Y337500D03*
X468300D03*
X456550D03*
X464300D03*
X460800Y337562D03*
X460300Y333500D03*
X467774Y362151D03*
X467100Y357500D03*
X464500Y347410D03*
X502138Y348500D03*
X476500Y347650D03*
X498138Y348500D03*
X506200Y358809D03*
X493200Y358800D03*
X498700Y359209D03*
X452600Y332700D03*
X462450Y358960D03*
X472463Y329837D03*
X468500Y347500D03*
X476200Y334900D03*
X506262Y348500D03*
X510138D03*
X479640Y334674D03*
X503800Y382700D03*
X473900Y371800D03*
X485100Y363400D03*
X510200Y363209D03*
X506200D03*
X494400Y363800D03*
X499100Y363409D03*
X452500Y423500D03*
X510700Y367309D03*
X506700D03*
X489600Y367209D03*
X474200Y367500D03*
X457599Y419642D03*
X496300Y378935D03*
X489500Y371200D03*
X546627Y324049D03*
X551127D03*
X545278Y315738D03*
X549778D03*
X545221Y308771D03*
X549721D03*
X541193Y301280D03*
X545193D03*
X549693D03*
X553693D03*
X552200Y339300D03*
X556800D03*
X547225Y357997D03*
X547379Y338352D03*
X539900Y338300D03*
X534000Y338400D03*
X538225Y357997D03*
X555697Y356565D03*
X514000Y359209D03*
X514138Y348500D03*
X518138Y348350D03*
X525438Y350500D03*
X519263Y327092D03*
X538476Y334365D03*
X538436Y330918D03*
X534100Y342410D03*
X536200Y348300D03*
X540200D03*
X550100D03*
X546100D03*
X554685Y333410D03*
X547927Y342199D03*
X543646Y342347D03*
X539446D03*
X519629Y330448D03*
X521914Y332907D03*
X557411Y481025D03*
X554250Y457500D03*
X574250Y466900D03*
X562460Y457580D03*
X517125Y488975D03*
X632416Y31609D03*
X627603Y43523D03*
X627500Y19339D03*
X626786Y31227D03*
X634400Y102000D03*
X630600D03*
X627500Y64500D03*
X629500Y61500D03*
X634169Y166500D03*
X618250Y162081D03*
X618400Y173443D03*
X617600Y134400D03*
X635852Y133715D03*
X627455Y185364D03*
X634000Y234200D03*
X630000D03*
X636363Y209944D03*
X632363D03*
X628363D03*
X624363D03*
X622400Y216750D03*
X633800Y239600D03*
X629900Y239700D03*
X633800Y245700D03*
X629900Y245800D03*
X634100Y252000D03*
X629900D03*
X618300Y288745D03*
X632750Y292195D03*
Y295641D03*
X594025Y280017D03*
X632750Y330854D03*
Y334300D03*
X632900Y344950D03*
X634000Y306300D03*
X631800Y316137D03*
X603650Y315500D03*
X594292Y362291D03*
X625000Y361700D03*
X590350Y323011D03*
X629250Y310491D03*
Y306491D03*
X626405Y314991D03*
X629250Y344900D03*
Y348900D03*
X623063Y357337D03*
X602649Y349033D03*
X594400Y357000D03*
Y353000D03*
X597450Y324750D03*
Y320750D03*
X627020Y393364D03*
X629770Y369320D03*
X594200Y390400D03*
X629400Y414324D03*
X584280Y424030D03*
X598023Y383081D03*
X624200Y372500D03*
X620260Y389940D03*
X589394Y384572D03*
X589391Y378202D03*
X627140Y381353D03*
X631140D03*
X594200Y395200D03*
X604832Y395220D03*
X630000Y464900D03*
X626300D03*
X577330Y464430D03*
X599900Y438300D03*
X587890Y426720D03*
X581020Y471890D03*
X574667Y479799D03*
X577300Y460300D03*
X588400Y469450D03*
X634050Y469200D03*
X588663Y460037D03*
X581250Y480550D03*
X585420Y456480D03*
X633676Y460080D03*
X617000Y468700D03*
X588030Y430795D03*
X620600Y458500D03*
X656300Y20100D03*
X660200Y20200D03*
X647216Y31601D03*
X667900Y40800D03*
X643816Y31573D03*
X640144Y40969D03*
X643103Y13803D03*
X664301Y40104D03*
Y49998D03*
X638103Y13100D03*
X640416Y31609D03*
X647103Y13964D03*
X694365Y94458D03*
Y90958D03*
X686279Y94494D03*
Y90994D03*
X678225Y94496D03*
Y90996D03*
X670146Y94505D03*
Y91005D03*
X662047Y94539D03*
Y91039D03*
X654037Y94708D03*
Y91208D03*
X654330Y113385D03*
X688976D03*
X644100Y111811D03*
X668100Y56100D03*
X651564Y52638D03*
X644500Y65759D03*
X657480Y113385D03*
X678189Y108784D03*
X689049Y109487D03*
X669500Y108400D03*
X640600Y111600D03*
X641003Y68809D03*
X654330Y154330D03*
X657480Y151219D03*
X663778Y166928D03*
X673227Y157479D03*
X673229Y166929D03*
Y173228D03*
X670080Y148030D03*
X679526Y144880D03*
X660629Y138584D03*
Y141732D03*
X688978Y135435D03*
X682679D03*
X676379D03*
X695274Y135431D03*
X698425Y129134D03*
X663778Y160629D03*
Y154330D03*
Y135431D03*
X692124D03*
X673227Y144880D03*
X685825Y138581D03*
X679526D03*
X673227D03*
X666928D03*
X648032Y129134D03*
X657480Y122834D03*
X698425Y135433D03*
Y138582D03*
X692125D03*
X682677Y148031D03*
X688976D03*
X695275D03*
X682677Y154330D03*
X688976D03*
X695275D03*
Y160629D03*
X688976D03*
X682677Y160630D03*
X679527Y163779D03*
X695275Y166929D03*
X688976D03*
X682677D03*
X695275Y173228D03*
X688976D03*
X682677D03*
X654330Y170078D03*
X648031Y163779D03*
X654330D03*
X651181Y157480D03*
X670078Y154330D03*
X644882Y157480D03*
X666929Y125984D03*
X657480Y129134D03*
X651181Y151181D03*
X698425Y116535D03*
X648059Y151191D03*
X685827Y125985D03*
X676377Y116536D03*
X663778Y176377D03*
Y173227D03*
Y170078D03*
X670078Y166928D03*
Y173227D03*
X654330Y176377D03*
X639108Y167800D03*
X648057Y141721D03*
X648032Y135434D03*
Y122835D03*
X660629Y116536D03*
X666929Y116535D03*
X698426Y122835D03*
X692148Y129119D03*
X670116Y132283D03*
X673229Y125985D03*
X679528D03*
X660629Y170078D03*
Y173227D03*
X654330Y157480D03*
X651181Y154330D03*
X673229Y170079D03*
X679527Y173229D03*
X692126Y141732D03*
X698425D03*
X679527Y148031D03*
X685826D03*
X692126D03*
X698425D03*
X679527Y154330D03*
X685826D03*
X692126D03*
X698425D03*
Y160629D03*
X692126D03*
X685826D03*
X679527D03*
X698425Y166929D03*
X692126D03*
X685826D03*
X679527D03*
X698425Y173228D03*
X692126D03*
X685826D03*
X676376Y132281D03*
X666929Y129134D03*
X660630Y160630D03*
X640775Y156218D03*
X648031Y157480D03*
X644882Y154331D03*
X637952Y142515D03*
X640500Y125000D03*
X660629Y144883D03*
X657481Y132284D03*
X670078Y151181D03*
X637343Y171335D03*
Y174835D03*
X657480Y154330D03*
X644882Y173228D03*
Y176378D03*
Y170078D03*
X648031D03*
X670078Y157480D03*
X673228Y148031D03*
X692126Y125984D03*
X685827Y116535D03*
X670079Y125985D03*
X682678D03*
X676378D03*
X688977D03*
X676378Y119686D03*
X666929Y119685D03*
X663780Y125985D03*
X657479Y116536D03*
X654330Y116535D03*
Y119685D03*
Y122834D03*
X657480Y125984D03*
X654331D03*
X654330Y129134D03*
Y132283D03*
Y135433D03*
X651181D03*
X654330Y138582D03*
Y141732D03*
Y144882D03*
X651181D03*
X654330Y148031D03*
Y151181D03*
X679452Y209815D03*
X651181Y188976D03*
X679527Y182679D03*
Y188975D03*
X676379Y182678D03*
X692126Y182676D03*
Y185827D03*
Y179527D03*
X676379Y192126D03*
X670080Y182678D03*
X697069Y207157D03*
X663400Y234100D03*
X663200Y238100D03*
X682676Y179526D03*
Y188975D03*
X682677Y182677D03*
X682676Y185826D03*
X676377Y201574D03*
Y204723D03*
X685826Y198424D03*
X663778Y182676D03*
Y179526D03*
X654330Y182676D03*
X660629Y192125D03*
X666929D03*
X660630Y198425D03*
X676377Y198424D03*
X685826Y201574D03*
X682677Y192125D03*
X688976D03*
X698425D03*
X640931Y181102D03*
X646594Y210875D03*
X640584Y194127D03*
X683913Y213313D03*
X695275Y198425D03*
X692125Y198423D03*
X686352Y207200D03*
X640363Y209944D03*
X638479Y230640D03*
X674023Y213815D03*
X640509Y177600D03*
X674172Y210095D03*
X679400Y213300D03*
X679527Y198424D03*
X697149Y219742D03*
X692949D03*
X695600Y240354D03*
X682700D03*
X695625Y282250D03*
X669125Y280405D03*
X663000Y249200D03*
X663100Y252700D03*
X674841Y262854D03*
X695383Y266855D03*
X644153Y278745D03*
X660400Y271900D03*
X668600Y242800D03*
X669450Y284900D03*
X695600Y244354D03*
X695375Y260875D03*
X637500Y362400D03*
X680300Y384900D03*
X662306Y365477D03*
X657673Y365400D03*
X672281Y378883D03*
X693500Y373300D03*
X642900Y395400D03*
X674150Y415380D03*
X654770Y401166D03*
X645970Y399130D03*
X669031Y388383D03*
X665031D03*
X653360Y386210D03*
X680700Y378200D03*
X687150Y385550D03*
X675031Y389383D03*
X653007Y382828D03*
X658601Y401800D03*
X673900Y418880D03*
X637500Y365900D03*
X692200Y428700D03*
X681540Y429640D03*
X678700Y440950D03*
X671640Y454410D03*
X683250Y437813D03*
X710378Y96399D03*
Y92899D03*
X702391Y94510D03*
Y91010D03*
X722673Y105444D03*
X736785Y110185D03*
X737800Y106525D03*
X717197Y109646D03*
X726100Y107200D03*
X734709Y106595D03*
X731000Y106315D03*
X734212Y109995D03*
X725943Y100147D03*
X744833Y78995D03*
X754572Y86923D03*
X754528Y83228D03*
X745100Y97500D03*
X699563Y108815D03*
X719010Y107281D03*
X707649Y110002D03*
X710517Y106823D03*
X750773Y74636D03*
X747919Y76667D03*
X720744Y92427D03*
X704849Y107385D03*
X733069Y166930D03*
X704725Y135434D03*
X707874Y141732D03*
X701574Y138582D03*
X701575Y135433D03*
X711023Y132283D03*
X704724D03*
X717322Y129133D03*
X726770Y166930D03*
Y173229D03*
X701574Y148031D03*
X707873D03*
X701574Y154330D03*
X707873D03*
Y160629D03*
X701574D03*
X707873Y166929D03*
X701574D03*
X707873Y173228D03*
X701574D03*
X711023Y122834D03*
X717322D03*
X723622D03*
X711023Y141732D03*
X743452Y151815D03*
X714172Y173227D03*
Y144880D03*
Y151180D03*
X717322Y144880D03*
Y151180D03*
X714172Y163778D03*
Y157479D03*
X717322Y163778D03*
Y157479D03*
Y166928D03*
X720472Y173228D03*
Y148031D03*
Y141732D03*
Y160629D03*
Y154330D03*
X720471Y166928D03*
X717322Y141731D03*
X758050Y164050D03*
X704725Y122835D03*
X720472Y135433D03*
X729921Y157480D03*
X739952Y120649D03*
X740952Y126815D03*
X707874Y116535D03*
X743100Y114700D03*
X737352Y145885D03*
X726771Y122835D03*
X729921Y122834D03*
X737702Y128565D03*
X729921Y132283D03*
Y129134D03*
X711023Y116535D03*
X726771Y163779D03*
X741754Y134617D03*
X729921Y135433D03*
X739622Y137008D03*
X729921Y138582D03*
Y144882D03*
X714173Y116535D03*
X717322D03*
X707873Y129133D03*
X720473Y116536D03*
X704725D03*
X704724Y148031D03*
Y154330D03*
Y160629D03*
Y166929D03*
Y173228D03*
X714173Y141732D03*
X723622Y116535D03*
X704723Y129133D03*
X701574D03*
X711022D03*
X714172D03*
X729921Y125984D03*
X711023Y173228D03*
X741952Y173115D03*
X738352Y174615D03*
X729920Y176378D03*
Y173229D03*
X736219Y170079D03*
X733070D03*
X746750Y157700D03*
X729921Y148031D03*
Y141732D03*
Y163779D03*
X750550Y135200D03*
X729921Y160629D03*
X701575Y116536D03*
X729921Y154330D03*
X717322Y182676D03*
X711024Y188976D03*
X701575Y182676D03*
X711022Y185825D03*
X701575Y185827D03*
Y179527D03*
X726770Y179528D03*
Y185827D03*
X743200Y227900D03*
X726770Y192126D03*
X730694Y224473D03*
X726656Y235244D03*
X711022Y179526D03*
X714172D03*
X722523Y221315D03*
X720437Y185829D03*
X720472Y179527D03*
Y192125D03*
X711022Y182676D03*
X704724Y192125D03*
X711024D03*
X715467Y210507D03*
X725009Y213292D03*
X739852Y195915D03*
X737832Y202664D03*
X729920Y188977D03*
X739752Y199615D03*
X738416Y190551D03*
X729920Y182678D03*
X745485Y197673D03*
Y201673D03*
X740352Y180115D03*
X729920Y185827D03*
X724776Y209963D03*
X743752Y187115D03*
X742502Y182715D03*
X742252Y177015D03*
X737315Y177952D03*
X733070Y179527D03*
X720819Y209800D03*
X729246Y209941D03*
X736272Y208181D03*
X729136Y206654D03*
X738839Y206080D03*
X733565Y210184D03*
X729920Y192126D03*
X720357Y207104D03*
X714173Y198425D03*
X729921Y179527D03*
X720471Y198424D03*
X731915Y206310D03*
X738952Y184215D03*
X744052Y193784D03*
X701574Y198424D03*
X711023Y198425D03*
X704724D03*
X717322D03*
X707873Y198424D03*
X723621D03*
X704724Y201574D03*
X706737Y205505D03*
X705336Y208437D03*
X711310Y207023D03*
X714173Y201574D03*
X718330Y205172D03*
X704708Y264647D03*
X751878Y276817D03*
X749620Y273620D03*
X754227Y297611D03*
X739300Y287611D03*
X751693Y255540D03*
X743507Y251685D03*
X747558Y247274D03*
X759558Y241027D03*
Y247274D03*
X731300Y287611D03*
X735300D03*
X731318Y283571D03*
X735318D03*
X731155Y279636D03*
X739318Y283571D03*
X734638Y275696D03*
X751693Y259540D03*
X755693D03*
X704708Y256647D03*
Y252647D03*
X753560Y273780D03*
X704708Y260647D03*
X751133Y313984D03*
X754227Y301111D03*
X735570Y424760D03*
X721380Y423930D03*
X739680Y423900D03*
X700200Y388200D03*
Y384800D03*
X743480Y439080D03*
X710200Y441200D03*
X706120Y441410D03*
X729870Y451300D03*
X740900Y456400D03*
X700855Y426719D03*
X761650Y89937D03*
X771610Y93040D03*
X799500Y106000D03*
X781000Y88000D03*
Y84200D03*
X788287Y86087D03*
X768250Y106300D03*
X768100Y109700D03*
X763560Y59820D03*
X767359Y82076D03*
X782500Y134283D03*
X773000Y119600D03*
X776600D03*
X794500Y134283D03*
X785000Y158900D03*
X760600Y173700D03*
X768700Y129800D03*
X768900Y134800D03*
X760715Y210200D03*
X804412Y185332D03*
X800612Y185432D03*
X760715Y201700D03*
Y214200D03*
X790000Y224700D03*
X786400Y179000D03*
X779200Y178650D03*
X790714Y237308D03*
X801618Y210116D03*
Y214116D03*
X795498Y246171D03*
X793912Y297020D03*
X793837Y283696D03*
X781640Y278660D03*
X786006Y283383D03*
X775486Y287316D03*
X805254Y263886D03*
X761484Y255581D03*
Y251581D03*
X780837Y240885D03*
X774637Y267746D03*
X770637D03*
X761638Y259635D03*
X774637Y259746D03*
Y263746D03*
X793837Y279636D03*
Y275696D03*
X780837Y267826D03*
X784837Y263891D03*
Y259951D03*
X793852Y256011D03*
Y252076D03*
X793837Y271761D03*
Y267826D03*
Y263696D03*
X774657Y255999D03*
X765638Y255635D03*
X774637Y251876D03*
X784837Y271761D03*
Y267826D03*
X793837Y287696D03*
X780837Y271761D03*
X801853Y300515D03*
X767890Y273380D03*
X763292Y287630D03*
X786610Y321340D03*
X786300Y309900D03*
X761520Y339110D03*
X765764Y326844D03*
X801728Y304572D03*
X776497Y338392D03*
X775672Y350204D03*
X782770Y321200D03*
G54D15*
X54900Y204700D03*
X49900Y209700D03*
X59900D03*
X54900Y214700D03*
Y209700D03*
X246493Y399567D03*
X242893D03*
X257020Y390670D03*
X253420D03*
X249820D03*
X246220D03*
X256120Y395170D03*
X243120D03*
X247620D03*
X251870D03*
X242620Y390670D03*
X260893Y399567D03*
X257293D03*
X260620Y390670D03*
Y395170D03*
X253693Y399567D03*
X250093D03*
X609400Y446850D03*
X604400Y456100D03*
Y451850D03*
Y447350D03*
Y460350D03*
X609400Y450450D03*
Y454050D03*
Y457650D03*
Y461250D03*
X599503Y447123D03*
Y450723D03*
Y454323D03*
Y457923D03*
X604400Y464850D03*
X609400D03*
X599503Y461523D03*
Y465123D03*
G54D23*
X98425Y472441D03*
X137795D03*
G54D28*
X388189Y44095D03*
X374016D03*
X359843D03*
X345670D03*
X388189Y38583D03*
X374016D03*
X359843D03*
X345670D03*
X388189Y29922D03*
X374016D03*
X359843D03*
X345670D03*
X388189Y24410D03*
X374016D03*
X359843D03*
X345670D03*
X388189Y15748D03*
X374016D03*
X359843D03*
X345670D03*
X388189Y10237D03*
X374016D03*
X359843D03*
X345670D03*
X381103Y48819D03*
X366929D03*
X352756D03*
X338583D03*
X381103Y43307D03*
X366929D03*
X352756D03*
X338583D03*
X381103Y34646D03*
X366929D03*
X352756D03*
X338583D03*
X381103Y29134D03*
X366929D03*
X352756D03*
X338583D03*
X381103Y20473D03*
X366929D03*
X352756D03*
X338583D03*
X381103Y14961D03*
X366929D03*
X352756D03*
X338583D03*
X444882Y44095D03*
X430709D03*
X416536D03*
X402363D03*
X444882Y38583D03*
X430709D03*
X416536D03*
X402363D03*
X444882Y29922D03*
X430709D03*
X416536D03*
X402363D03*
X444882Y24410D03*
X430709D03*
X416536D03*
X402363D03*
X444882Y15748D03*
X430709D03*
X416536D03*
X402363D03*
X444882Y10237D03*
X430709D03*
X416536D03*
X402363D03*
X437796Y48819D03*
X423622D03*
X409449D03*
X395276D03*
X437796Y43307D03*
X423622D03*
X409449D03*
X395276D03*
X437796Y34646D03*
X423622D03*
X409449D03*
X395276D03*
X437796Y29134D03*
X423622D03*
X409449D03*
X395276D03*
X437796Y20473D03*
X423622D03*
X409449D03*
X395276D03*
X437796Y14961D03*
X423622D03*
X409449D03*
X395276D03*
X401575Y410039D03*
X410433D03*
X419292D03*
X404528Y412795D03*
X413386D03*
X422244D03*
X401575Y425000D03*
X410433D03*
X419292D03*
X407480Y422244D03*
X416339D03*
X425197D03*
X407480Y407284D03*
X416339D03*
X425197D03*
X404528Y427756D03*
X413386D03*
X422244D03*
X401575Y439961D03*
X410433D03*
X419292D03*
X404528Y442717D03*
X413386D03*
X422244D03*
X401575Y454921D03*
X410433D03*
X419292D03*
X404528Y457677D03*
X413386D03*
X422244D03*
X407480Y437205D03*
X416339D03*
X425197D03*
X407480Y452165D03*
X416339D03*
X425197D03*
X501575Y44095D03*
X487402D03*
X473229D03*
X459055D03*
X501575Y38583D03*
X487402D03*
X473229D03*
X459055D03*
X501575Y29922D03*
X487402D03*
X473229D03*
X459055D03*
X501575Y24410D03*
X487402D03*
X473229D03*
X459055D03*
X501575Y15748D03*
X487402D03*
X473229D03*
X459055D03*
X501575Y10237D03*
X487402D03*
X473229D03*
X459055D03*
X508662Y48819D03*
X494489D03*
X480315D03*
X466142D03*
X451969D03*
X508662Y43307D03*
X494489D03*
X480315D03*
X466142D03*
X451969D03*
X508662Y34646D03*
X494489D03*
X480315D03*
X466142D03*
X451969D03*
X508662Y29134D03*
X494489D03*
X480315D03*
X466142D03*
X451969D03*
X508662Y20473D03*
X494489D03*
X480315D03*
X466142D03*
X451969D03*
X508662Y14961D03*
X494489D03*
X480315D03*
X466142D03*
X451969D03*
X572441Y44095D03*
X558268D03*
X544095D03*
X529922D03*
X515748D03*
X572441Y38583D03*
X558268D03*
X544095D03*
X529922D03*
X515748D03*
X572441Y29922D03*
X558268D03*
X544095D03*
X529922D03*
X515748D03*
X572441Y24410D03*
X558268D03*
X544095D03*
X529922D03*
X515748D03*
X572441Y15748D03*
X558268D03*
X544095D03*
X529922D03*
X515748D03*
X572441Y10237D03*
X558268D03*
X544095D03*
X529922D03*
X515748D03*
X565355Y48819D03*
X551181D03*
X537008D03*
X522835D03*
X565355Y43307D03*
X551181D03*
X537008D03*
X522835D03*
X565355Y34646D03*
X551181D03*
X537008D03*
X522835D03*
X565355Y29134D03*
X551181D03*
X537008D03*
X522835D03*
X565355Y20473D03*
X551181D03*
X537008D03*
X522835D03*
X565355Y14961D03*
X551181D03*
X537008D03*
X522835D03*
X586614Y44095D03*
Y38583D03*
Y29922D03*
Y24410D03*
Y15748D03*
Y10237D03*
X579528Y48819D03*
Y43307D03*
Y34646D03*
Y29134D03*
Y20473D03*
Y14961D03*
X758267Y44095D03*
X744094D03*
X729921D03*
X715748D03*
X758267Y38583D03*
X744094D03*
X729921D03*
X715748D03*
X758267Y29922D03*
X744094D03*
X729921D03*
X715748D03*
X758267Y24410D03*
X744094D03*
X729921D03*
X715748D03*
X758267Y15748D03*
X744094D03*
X729921D03*
X715748D03*
X758267Y10237D03*
X744094D03*
X729921D03*
X715748D03*
X751181Y48819D03*
X737007D03*
X722834D03*
X708661D03*
X751181Y43307D03*
X737007D03*
X722834D03*
X708661D03*
X751181Y34646D03*
X737007D03*
X722834D03*
X708661D03*
X751181Y29134D03*
X737007D03*
X722834D03*
X708661D03*
X751181Y20473D03*
X737007D03*
X722834D03*
X708661D03*
X751181Y14961D03*
X737007D03*
X722834D03*
X708661D03*
G54D34*
X410236Y419291D03*
Y404331D03*
Y449212D03*
Y434252D03*
G54D11*
X15364Y5500D03*
X10364D03*
X5500Y10384D03*
Y15384D03*
Y20384D03*
Y25384D03*
Y30384D03*
Y35384D03*
Y40384D03*
Y45384D03*
Y50384D03*
Y55384D03*
Y60384D03*
Y65384D03*
Y70384D03*
Y75384D03*
Y80384D03*
Y85384D03*
Y90384D03*
Y95384D03*
Y100384D03*
Y105384D03*
Y110384D03*
Y115384D03*
Y120384D03*
Y125384D03*
Y130384D03*
Y135384D03*
Y140384D03*
Y145384D03*
Y150384D03*
Y155384D03*
Y160384D03*
Y165384D03*
Y170384D03*
Y175384D03*
Y180384D03*
Y185384D03*
Y190384D03*
Y195384D03*
Y200384D03*
Y205384D03*
Y210384D03*
Y215384D03*
Y220384D03*
Y225384D03*
Y230384D03*
Y235384D03*
Y240384D03*
Y245384D03*
Y250384D03*
Y255384D03*
Y260384D03*
Y265384D03*
Y270384D03*
Y275384D03*
Y280384D03*
Y285384D03*
Y290384D03*
Y295384D03*
Y300384D03*
Y305384D03*
Y310384D03*
Y315384D03*
Y320384D03*
Y325384D03*
Y330384D03*
Y335384D03*
Y340384D03*
Y345384D03*
Y350384D03*
Y355384D03*
Y360384D03*
Y365384D03*
Y370384D03*
Y375384D03*
Y380384D03*
Y385384D03*
Y390384D03*
Y395384D03*
Y400384D03*
Y405384D03*
Y410384D03*
Y415384D03*
Y420384D03*
Y425384D03*
Y430384D03*
Y435384D03*
Y440384D03*
Y445384D03*
Y450384D03*
Y455384D03*
Y460384D03*
Y465384D03*
Y470384D03*
Y475384D03*
Y480384D03*
Y485384D03*
Y530384D03*
Y525384D03*
Y520384D03*
Y515384D03*
Y510384D03*
Y505384D03*
Y490384D03*
Y495384D03*
Y500384D03*
Y535384D03*
Y540384D03*
Y545384D03*
Y550384D03*
Y555384D03*
Y560384D03*
X10266Y565366D03*
X15266D03*
X75364Y5500D03*
X70364D03*
X65364D03*
X60364D03*
X55364D03*
X50364D03*
X45364D03*
X40364D03*
X35364D03*
X30364D03*
X25364D03*
X20364D03*
X75119Y111166D03*
X20266Y565366D03*
X25266D03*
X30266D03*
X35266D03*
X40266D03*
X45266D03*
X50266D03*
X55266D03*
X60266D03*
X65266D03*
X70266D03*
X75266D03*
X95364Y5500D03*
X90364D03*
X85364D03*
X80364D03*
X105619Y111166D03*
X81119D03*
X87619D03*
X93619D03*
X99619D03*
X94080Y448470D03*
X80266Y565366D03*
X85266D03*
X90266D03*
X95266D03*
X100266D03*
X105266D03*
X110266D03*
X115266D03*
X120266D03*
X125266D03*
X130266D03*
X135266D03*
X198557Y153196D03*
X177850Y324800D03*
X174995Y353588D03*
Y358388D03*
X165195D03*
X169995D03*
Y353588D03*
X157650Y418100D03*
X160400Y422900D03*
X160550Y414100D03*
X142865Y424021D03*
X143608Y415900D03*
X158067Y378857D03*
X160400Y427700D03*
Y432500D03*
X145392Y445207D03*
X145456Y440338D03*
X142991Y430900D03*
X200266Y565366D03*
X195266D03*
X190266D03*
X185266D03*
X180266D03*
X175266D03*
X140266D03*
X145266D03*
X150266D03*
X155266D03*
X160266D03*
X165266D03*
X170266D03*
X222800Y204600D03*
X227600D03*
X222800Y219000D03*
X227600D03*
X222800Y214200D03*
X227600D03*
X222800Y209400D03*
X227600D03*
X222490Y235373D03*
X227290D03*
X222246Y229952D03*
X227046D03*
X222800Y223800D03*
X227600D03*
X222460Y240264D03*
X227260D03*
X254300Y357732D03*
X222818Y364806D03*
X222909Y371864D03*
X223000Y378246D03*
X246700Y418600D03*
X209052Y470198D03*
X213700Y448450D03*
X208900D03*
X203000Y451300D03*
X204252Y470198D03*
X204364Y478917D03*
X209164D03*
X212589Y494694D03*
X220589D03*
X216589Y489694D03*
X208589D03*
X224589D03*
X205266Y565366D03*
X210266D03*
X215266D03*
X220266D03*
X225266D03*
X230266D03*
X235266D03*
X240266D03*
X245266D03*
X250266D03*
X255266D03*
X260266D03*
X287300Y173000D03*
X292100D03*
X295650Y169554D03*
X295801Y210294D03*
X292600Y214500D03*
X287800D03*
X295879Y255540D03*
X291079D03*
X286279D03*
X276070Y395357D03*
X265266Y565366D03*
X270266D03*
X275266D03*
X280266D03*
X285266D03*
X290266D03*
X295266D03*
X300266D03*
X305266D03*
X310266D03*
X315266D03*
X320266D03*
X325266D03*
X350586Y495815D03*
X355523Y495025D03*
X360461Y494236D03*
X365398Y493446D03*
X370335Y492656D03*
X375272Y491866D03*
X380210Y491077D03*
X385169Y490563D03*
X329156Y545492D03*
Y540492D03*
Y535492D03*
Y530492D03*
Y525492D03*
Y520492D03*
Y515492D03*
Y560492D03*
Y555492D03*
Y550492D03*
X405169Y490563D03*
X410169D03*
X415169D03*
X420169D03*
X425169D03*
X430169D03*
X435169D03*
X440169D03*
X445146Y490850D03*
X450083Y491640D03*
X390169Y490563D03*
X395169D03*
X400169D03*
X490877Y176547D03*
X510427Y176431D03*
X500302Y176489D03*
X490877Y189047D03*
Y185047D03*
Y180547D03*
X510427Y188931D03*
Y184931D03*
Y180431D03*
X500302Y188989D03*
Y184989D03*
Y180489D03*
X505500Y464400D03*
Y469200D03*
Y474000D03*
X509500Y450800D03*
Y446000D03*
Y441200D03*
X469832Y494799D03*
X474769Y495589D03*
X455020Y492430D03*
X459958Y493219D03*
X464895Y494009D03*
X497636Y515532D03*
Y520532D03*
Y525532D03*
Y530532D03*
Y535532D03*
Y540532D03*
Y545532D03*
Y550532D03*
Y555532D03*
Y560532D03*
X502550Y565366D03*
X507550D03*
X512550D03*
X520552Y176373D03*
X557500Y231900D03*
X553500D03*
X549000D03*
X545000D03*
X520552Y188873D03*
Y184873D03*
Y180373D03*
X554717Y255796D03*
X550717D03*
X546217D03*
X542217D03*
X554975Y248209D03*
X550975D03*
X546475D03*
X542475D03*
X555865Y240638D03*
X551865D03*
X547365D03*
X543365D03*
X570234Y298026D03*
X572634Y293526D03*
X571300Y414800D03*
X567200Y407700D03*
X572062Y384378D03*
X527742Y425481D03*
X522942D03*
X518142D03*
X527742Y432481D03*
X522942D03*
X518142D03*
X529500Y471500D03*
X551400Y437800D03*
X545900D03*
X539800Y437900D03*
X517550Y565366D03*
X522550D03*
X527550D03*
X532550D03*
X537550D03*
X542550D03*
X547550D03*
X552550D03*
X557550D03*
X562550D03*
X567550D03*
X572550D03*
X576797Y113877D03*
X589706Y174031D03*
X586081Y158407D03*
X585145Y162809D03*
X595402Y149579D03*
X594466Y153981D03*
X588070Y138220D03*
X587134Y142622D03*
X576868Y127381D03*
X575932Y131783D03*
X582554Y116361D03*
X589135Y214107D03*
X588199Y218509D03*
X585010Y198483D03*
X584074Y202885D03*
X580885Y182859D03*
X579949Y187261D03*
X588770Y178433D03*
X575134Y298026D03*
X577534Y293526D03*
X580034Y298026D03*
X580900Y414800D03*
X576100D03*
X632150Y389100D03*
X576862Y384378D03*
X581087Y379569D03*
X576287D03*
X581692Y384378D03*
X628113Y428617D03*
X623313D03*
X618513D03*
X613713D03*
X605534Y480027D03*
X619600Y446100D03*
X629200D03*
X624400D03*
X577550Y565366D03*
X582550D03*
X587550D03*
X592550D03*
X597550D03*
X602550D03*
X607550D03*
X612550D03*
X617550D03*
X622550D03*
X627550D03*
X632550D03*
X655964Y52248D03*
X675136Y268500D03*
X637705Y298765D03*
X642705D03*
X659977Y323082D03*
X664731Y324099D03*
X660115Y351977D03*
Y356777D03*
X664731Y343299D03*
X655500Y360000D03*
X660115Y361577D03*
X664731Y338499D03*
Y333699D03*
Y328899D03*
X659977Y342282D03*
Y332682D03*
Y347082D03*
Y337482D03*
Y327882D03*
X696900Y337800D03*
X697500Y358200D03*
X637705Y303765D03*
X642705D03*
X674700Y306300D03*
X679500D03*
Y311100D03*
X674700D03*
X679500Y315900D03*
X674700D03*
X684400Y400100D03*
X637550Y389050D03*
X655532Y425245D03*
X658032Y420245D03*
X653032D03*
X653200Y408800D03*
X688500Y484400D03*
X675700Y468000D03*
Y463500D03*
X675400Y472300D03*
X659000Y428900D03*
X652200Y429100D03*
X688500Y488600D03*
X637550Y565366D03*
X642550D03*
X647550D03*
X652550D03*
X657550D03*
X662550D03*
X742200Y340800D03*
Y345600D03*
X737400Y340800D03*
Y345600D03*
X732600Y331200D03*
Y336000D03*
Y340800D03*
Y355200D03*
Y350400D03*
Y345600D03*
X701100Y315900D03*
X705900D03*
X701100Y311100D03*
X705900D03*
Y306300D03*
X701100D03*
X714600Y338900D03*
Y348500D03*
Y343700D03*
X709800Y348500D03*
Y343700D03*
X706500Y337800D03*
X701700D03*
X707100Y358200D03*
X702300D03*
X722100Y368300D03*
X717300D03*
X712500D03*
X742200Y380400D03*
Y370800D03*
Y375600D03*
X728700Y381000D03*
Y376200D03*
Y371400D03*
X722100Y363500D03*
X717300D03*
X712500D03*
X704340Y468062D03*
X705400Y477400D03*
X821272Y114340D03*
Y109340D03*
Y104340D03*
Y174340D03*
Y169340D03*
Y164340D03*
Y159340D03*
Y154340D03*
Y149340D03*
Y144340D03*
Y139340D03*
Y134340D03*
Y129340D03*
Y124340D03*
Y119340D03*
Y234340D03*
Y229340D03*
Y224340D03*
Y219340D03*
Y214340D03*
Y209340D03*
Y204340D03*
Y199340D03*
Y194340D03*
Y189340D03*
Y184340D03*
Y179340D03*
X771083Y211784D03*
X821272Y299340D03*
Y294340D03*
Y289340D03*
Y284340D03*
Y279340D03*
Y274340D03*
Y269340D03*
Y264340D03*
Y259340D03*
Y254340D03*
Y249340D03*
Y244340D03*
Y239340D03*
Y359340D03*
Y354340D03*
Y349340D03*
Y344340D03*
Y339340D03*
Y334340D03*
Y329340D03*
Y324340D03*
Y319340D03*
Y314340D03*
Y309340D03*
Y304340D03*
Y424340D03*
Y419340D03*
Y414340D03*
Y409340D03*
Y404340D03*
Y399340D03*
Y394340D03*
Y389340D03*
Y384340D03*
Y379340D03*
Y374340D03*
Y369340D03*
Y364340D03*
Y479340D03*
Y474340D03*
Y469340D03*
Y464340D03*
Y459340D03*
Y454340D03*
Y449340D03*
Y444340D03*
Y439340D03*
Y434340D03*
Y429340D03*
G54D17*
X37402Y499724D03*
X789370D03*
G54D30*
X374432Y316002D03*
X421258Y232283D03*
X448818Y232284D03*
X440944D03*
X433070D03*
X433071Y224410D03*
X440945D03*
X448819D03*
X397638Y232284D03*
X389764Y204725D03*
Y220473D03*
Y208662D03*
Y228347D03*
X409449Y236221D03*
X393701Y228347D03*
Y216536D03*
Y212599D03*
X397638D03*
X401575D03*
X393701Y220473D03*
X397638Y200788D03*
X405512D03*
X413386D03*
X421260D03*
X429134D03*
X437008D03*
X444882D03*
X409449Y212599D03*
Y224410D03*
X417323Y212599D03*
X425197D03*
X433071D03*
X440945D03*
X448819D03*
X425197Y224410D03*
X417323D03*
X413386D03*
X409449Y232284D03*
X397638Y236221D03*
Y228347D03*
Y224410D03*
X389000Y236100D03*
X401575Y236221D03*
X405512D03*
X417322D03*
X409449Y220473D03*
Y216536D03*
X413386Y220473D03*
Y216536D03*
X417323Y220473D03*
Y216536D03*
X421260Y220473D03*
Y216536D03*
X425197Y220473D03*
Y216536D03*
X429134Y220473D03*
Y216536D03*
X433071Y220473D03*
Y216536D03*
X437008Y220473D03*
Y216536D03*
X440945Y220473D03*
Y216536D03*
X444882Y220473D03*
Y216536D03*
X448819Y220473D03*
Y216536D03*
X409449Y204725D03*
Y200788D03*
X413386Y208662D03*
Y204725D03*
X417323D03*
Y200788D03*
X421260Y208662D03*
Y204725D03*
X425197D03*
Y200788D03*
X429134Y208662D03*
Y204725D03*
X433071D03*
Y200788D03*
X437008Y208662D03*
Y204725D03*
X440945D03*
Y200788D03*
X444882Y208662D03*
Y204725D03*
X448819D03*
Y200788D03*
X389764Y216536D03*
Y212599D03*
X397638Y220473D03*
Y216536D03*
X401575Y220473D03*
Y216536D03*
X405512Y220473D03*
Y216536D03*
X393701Y204725D03*
Y200788D03*
X397638Y208662D03*
Y204725D03*
X401575D03*
Y200788D03*
X405512Y208662D03*
Y204725D03*
X401575Y232284D03*
X401727Y228641D03*
X405512Y232284D03*
X413386D03*
X405512Y228347D03*
X409449Y259843D03*
X425197Y291339D03*
X433071Y295276D03*
Y299213D03*
Y291339D03*
X448819Y287403D03*
X448818Y291339D03*
Y295276D03*
X437008Y299213D03*
Y291339D03*
X448818Y299214D03*
X425196Y283466D03*
X433070Y279528D03*
X433071Y275591D03*
X433070Y255905D03*
X437057Y279414D03*
X397638Y240158D03*
Y295276D03*
X405512D03*
X397638Y271654D03*
X409449Y267717D03*
X397638Y287402D03*
X405512D03*
X397638Y279528D03*
X409449Y275591D03*
X397638Y259843D03*
X405512D03*
Y255906D03*
X389764Y251969D03*
X393701D03*
X397638D03*
X409449Y244095D03*
Y255906D03*
X417323Y299213D03*
X421260Y291339D03*
X425197Y259843D03*
X417323Y267717D03*
X429134Y271654D03*
X417323Y275591D03*
X429134Y248032D03*
X425197Y255906D03*
X417323D03*
X413386Y259843D03*
X429134Y279528D03*
X421260D03*
X433071Y240158D03*
Y248032D03*
X448819Y240158D03*
X440945D03*
X444882Y279529D03*
X448819Y248032D03*
X440945D03*
X448818Y259843D03*
Y267718D03*
X440944D03*
X433071Y263781D03*
X440944Y259843D03*
X429134Y295277D03*
Y299214D03*
X437007Y287402D03*
X429134Y291340D03*
X421260Y259843D03*
X429134Y263781D03*
Y255906D03*
X433071Y283465D03*
X425197Y287402D03*
X444882D03*
X440945Y283465D03*
X448819D03*
X444882Y299213D03*
X425196Y240158D03*
X409449D03*
Y248032D03*
X397638Y244095D03*
X421260Y255906D03*
X425197Y299213D03*
X429134Y287403D03*
X417323Y259843D03*
X413386Y255906D03*
X440945Y295276D03*
Y299213D03*
Y291339D03*
Y287402D03*
X437008Y295276D03*
X429134Y251969D03*
X417323D03*
X413386Y248032D03*
X405512D03*
X421260Y251969D03*
X405512Y244095D03*
X401575D03*
X413386D03*
X417323Y248032D03*
X401575Y240158D03*
X405512D03*
X433070Y287402D03*
X413387Y240158D03*
X421260Y248032D03*
X417323Y244095D03*
X413386Y251969D03*
X401575Y248032D03*
X421260Y295277D03*
X448819Y244095D03*
X440945D03*
X433071D03*
X421259Y240158D03*
X421260Y244095D03*
X417323Y240157D03*
X421260Y299214D03*
X425197Y295276D03*
X413386Y311025D03*
X425197Y318898D03*
Y303150D03*
X429134Y314961D03*
Y311024D03*
X448819Y307088D03*
X448818Y311024D03*
Y303151D03*
X444882Y314961D03*
Y318898D03*
X433071Y314961D03*
X431102Y331263D03*
X397638Y326772D03*
X409449D03*
X397638Y318898D03*
X409449D03*
Y314961D03*
X397638Y311024D03*
X409449D03*
X417323Y326772D03*
Y318898D03*
X425197Y311024D03*
X433071D03*
X397638Y303150D03*
X405512D03*
X413386Y307087D03*
X440945Y318898D03*
X448819D03*
X417323Y307087D03*
Y303150D03*
X429134Y303151D03*
X425197Y314961D03*
X413386Y326772D03*
X425197Y307087D03*
X417323Y314961D03*
X433071Y307087D03*
X448819Y314961D03*
X440945D03*
X417323Y311024D03*
X429134Y318898D03*
X442800Y330300D03*
X446200Y327400D03*
X440945Y303150D03*
Y311024D03*
Y307087D03*
X444881Y322835D03*
X442913Y327204D03*
X440944Y322835D03*
X438976Y327204D03*
X437008Y318898D03*
Y314961D03*
Y311024D03*
Y303150D03*
Y307087D03*
X433071Y318898D03*
X421260Y326772D03*
X421259Y322835D03*
X421260Y318898D03*
Y314961D03*
X417322Y322835D03*
X413386Y314962D03*
X421260Y307088D03*
X433071Y303150D03*
X421260Y303151D03*
X456693Y232284D03*
X464567D03*
X472441D03*
X480315D03*
X456693Y200788D03*
X464567D03*
X492126Y208662D03*
Y204725D03*
X500000D03*
X472441Y200788D03*
X480315D03*
X488189D03*
X492126D03*
X460630Y212599D03*
X468504D03*
X492126Y216536D03*
X476378Y212599D03*
X484252D03*
X492126D03*
X503937D03*
X507874Y208662D03*
X503937Y204725D03*
X507874D03*
X503937Y236221D03*
Y228347D03*
X492126Y220473D03*
X503937D03*
X511811Y208662D03*
X507874Y200788D03*
X511811D03*
X472441Y224410D03*
X464567D03*
X456693D03*
X480315D03*
X492126D03*
X488189D03*
X492126Y232284D03*
Y236221D03*
X500000Y200788D03*
X503937D03*
X456693Y220473D03*
Y216536D03*
X460630Y220473D03*
Y216536D03*
X464567Y220473D03*
Y216536D03*
X468504Y220473D03*
Y216536D03*
X472441Y220473D03*
Y216536D03*
X476378Y220473D03*
Y216536D03*
X480315Y220473D03*
Y216536D03*
X484252Y220473D03*
Y216536D03*
X488189Y220473D03*
Y216536D03*
X500000Y208662D03*
X503937D03*
X496063Y212599D03*
X500000D03*
X496063Y216536D03*
X500000D03*
X496063Y220473D03*
X500000D03*
X496063Y224410D03*
X500000D03*
X496063Y228347D03*
X500000D03*
X496063Y232284D03*
X500000D03*
X496063Y236221D03*
X500000D03*
X456693Y208662D03*
Y204725D03*
X460630D03*
Y200788D03*
X464567Y208662D03*
Y204725D03*
X468504D03*
Y200788D03*
X472441Y208662D03*
Y204725D03*
X476378D03*
Y200788D03*
X480315Y208662D03*
Y204725D03*
X484252D03*
Y200788D03*
X488189Y208662D03*
Y204725D03*
X468504Y299214D03*
X472442Y287402D03*
X480315Y295276D03*
X484252Y295277D03*
X476378Y291339D03*
X452755Y287402D03*
Y291340D03*
Y295277D03*
X464567Y299214D03*
X456693Y279528D03*
Y267718D03*
X464567D03*
X472441Y295276D03*
X503937Y251969D03*
Y244095D03*
Y271654D03*
Y259843D03*
Y287402D03*
Y279528D03*
Y295276D03*
X488189Y287402D03*
X492126Y291339D03*
X488189D03*
X472441Y240158D03*
X456693Y259843D03*
X464567Y240158D03*
X456693D03*
X480315Y267717D03*
Y271654D03*
Y275591D03*
Y279528D03*
Y283465D03*
X492126Y267717D03*
X488189Y271654D03*
X492126Y275591D03*
X488189Y279528D03*
X492126Y283465D03*
X480315Y259843D03*
Y240158D03*
Y244095D03*
Y248032D03*
Y251969D03*
Y255906D03*
X488189Y259843D03*
X492126Y240158D03*
X488189D03*
X492126Y248032D03*
X488189D03*
Y255906D03*
X452757Y279529D03*
X464567D03*
X472441Y275591D03*
Y267717D03*
Y283465D03*
Y259843D03*
Y251969D03*
X456693Y248032D03*
X464567D03*
Y259843D03*
X472441Y291339D03*
X464568Y287402D03*
X476379D03*
X472441Y299213D03*
X480315D03*
X488189D03*
X456693Y287402D03*
X460630Y283465D03*
X468504D03*
X468505Y287402D03*
X460631Y295277D03*
X456693Y299213D03*
X460630D03*
X480316Y287403D03*
X484252Y291340D03*
Y287402D03*
X488189Y295276D03*
X456694D03*
X496063Y255906D03*
X500000D03*
X496063Y259843D03*
X500000D03*
X496063Y267717D03*
X500000D03*
X496063Y240158D03*
X500000D03*
X496063Y244095D03*
X500000D03*
X496063Y271654D03*
X500000D03*
X496063Y248032D03*
X500000D03*
X496063Y251969D03*
X500000D03*
X496063Y275591D03*
X500000D03*
X496063Y279528D03*
X500000D03*
X496063Y283465D03*
X500000D03*
X496063Y287402D03*
X500000D03*
X507874Y255906D03*
X511811D03*
Y259843D03*
X507874Y267717D03*
X511811D03*
X507874Y240158D03*
X511811D03*
Y244095D03*
Y271654D03*
X507874Y248032D03*
X511811D03*
Y251969D03*
X507874Y275591D03*
X511811D03*
Y279528D03*
X507874Y283465D03*
X511811D03*
Y287402D03*
X480315Y291339D03*
X496063Y299213D03*
X500000D03*
X496063Y291339D03*
X500000D03*
X496063Y295276D03*
X500000D03*
X476378Y267717D03*
Y275591D03*
Y259843D03*
Y251969D03*
X472441Y244095D03*
X464567D03*
X456693D03*
Y291339D03*
X460630D03*
X500001Y314961D03*
X503937Y318898D03*
X488189Y307087D03*
X492126Y311024D03*
X460630Y307087D03*
X456693D03*
X460630Y311024D03*
X462599Y327204D03*
X456693Y311024D03*
Y314961D03*
X452755Y307087D03*
Y303150D03*
X456693Y318898D03*
X472441Y303150D03*
X460630Y318898D03*
X468504D03*
X456693Y303150D03*
X476378Y318898D03*
X480315Y303150D03*
X492126D03*
X503937D03*
X484252D03*
X496063Y318898D03*
X488189Y311024D03*
X484252Y307087D03*
Y314961D03*
X476378D03*
X468504D03*
X507874D03*
X492126D03*
X500000Y311025D03*
X460630Y314961D03*
X496063D03*
X476378Y311024D03*
X472441Y307087D03*
X488189Y303150D03*
X500000Y307088D03*
X503937Y311024D03*
X468504Y303151D03*
X460630Y303150D03*
X464567Y303151D03*
X503937Y307087D03*
X507874Y311024D03*
X464567Y307088D03*
X468505D03*
X472441Y314961D03*
X492126Y307087D03*
X496063Y311024D03*
X464567Y311025D03*
Y318898D03*
X472441D03*
X496063Y303150D03*
X500000D03*
X470473Y327204D03*
X468504Y311024D03*
X488189Y322835D03*
X517000Y226370D03*
Y218500D03*
Y234252D03*
X517500Y297218D03*
X518647Y288943D03*
X515748Y240158D03*
Y267717D03*
Y255906D03*
Y248032D03*
Y283465D03*
Y275591D03*
Y259843D03*
Y244095D03*
Y271654D03*
Y251969D03*
Y279528D03*
Y287402D03*
X516500Y313000D03*
X666928Y144880D03*
X682675Y132281D03*
X688974D03*
X660630Y122834D03*
X660629Y119685D03*
X663779Y122834D03*
Y119685D03*
X670079Y122835D03*
X670078Y119685D03*
X673229Y122835D03*
X673228Y119685D03*
X679528Y122835D03*
X679527Y119685D03*
X682678Y122835D03*
X682677Y119685D03*
X688977Y122835D03*
X688976Y119685D03*
X692126Y122835D03*
Y119686D03*
G54D22*
X140000Y204950D03*
X201400Y174400D03*
X192400D03*
X196900D03*
X179800Y133500D03*
X175800Y129500D03*
X179800D03*
X175800Y133500D03*
X170900Y160500D03*
X151500D03*
X156300D03*
X161100D03*
X165900D03*
X192400Y191600D03*
X196900D03*
X201400D03*
X192400Y187300D03*
X196900D03*
X201400D03*
Y178700D03*
X192400Y183000D03*
X196900D03*
X201400D03*
X192400Y178700D03*
X196900D03*
X151500Y205000D03*
X156300D03*
X161100D03*
X165900D03*
X170900D03*
X178450Y203150D03*
X144800Y204950D03*
X268000Y165962D03*
X268064Y171792D03*
Y184062D03*
X268118Y191305D03*
X268000Y196800D03*
Y178062D03*
X539040Y480090D03*
X631864Y51848D03*
X635000Y427784D03*
X694365Y98458D03*
Y86958D03*
X686279Y98494D03*
Y86994D03*
X678225Y98496D03*
Y86996D03*
X670146Y98505D03*
Y87005D03*
X662047Y98539D03*
Y87039D03*
X654037Y98708D03*
Y87208D03*
X694400Y452900D03*
Y457400D03*
Y461900D03*
X689900Y457400D03*
Y452950D03*
X689700Y461850D03*
X639120Y462230D03*
X710378Y100399D03*
Y88899D03*
X702391Y98510D03*
Y87010D03*
X705900Y386900D03*
X711000Y395100D03*
X710900Y386800D03*
X706000Y395100D03*
X698900Y457400D03*
X699000Y452950D03*
X698950Y461800D03*
G54D13*
X71200Y137200D03*
X128580Y170810D03*
X122984Y170984D03*
X123200Y175800D03*
X125741Y166309D03*
X128459Y175658D03*
X158267Y25708D03*
X145669D03*
X158267Y47362D03*
X145669D03*
X158267Y53267D03*
Y41456D03*
Y31614D03*
Y19803D03*
X145669D03*
Y31614D03*
Y41456D03*
Y53267D03*
X200364Y5500D03*
X195364D03*
X190364D03*
X185364D03*
X180364D03*
X175364D03*
X170364D03*
X191000Y110000D03*
X192830Y170500D03*
X197630D03*
X192830Y165700D03*
X197630D03*
X192830Y160900D03*
X197630D03*
X196963Y122029D03*
X184600Y137400D03*
X195400Y147200D03*
X195500Y142400D03*
X191900Y196100D03*
X196900D03*
X201700D03*
X196900Y200900D03*
X191900D03*
X196900Y205700D03*
X191900D03*
X196900Y210500D03*
X191900D03*
X201700Y205700D03*
Y200900D03*
X197718Y350937D03*
Y355859D03*
X177468Y417900D03*
X176311Y445493D03*
X176423Y440472D03*
X177421Y432909D03*
X177532Y426134D03*
X260364Y5500D03*
X255364D03*
X250364D03*
X245364D03*
X240364D03*
X235364D03*
X230364D03*
X225364D03*
X220364D03*
X215364D03*
X210364D03*
X205364D03*
X242610Y53714D03*
X245250Y98250D03*
X261102Y77900D03*
X223994Y63225D03*
X242727Y63391D03*
X222700Y149300D03*
X227500D03*
X222700Y144500D03*
X227500D03*
X222700Y139700D03*
X227500D03*
X222700Y158900D03*
X227500D03*
X222700Y154100D03*
X227500D03*
X202430Y170500D03*
Y165700D03*
Y160900D03*
X253600Y139500D03*
Y134700D03*
X251800Y153600D03*
Y144000D03*
Y148800D03*
X258400Y134700D03*
Y139500D03*
X263200Y134700D03*
Y139500D03*
X253600Y230500D03*
Y225700D03*
Y220900D03*
X258400Y230500D03*
Y225700D03*
Y220900D03*
X263200Y230500D03*
Y225700D03*
Y220900D03*
X249204Y244103D03*
X312840Y42398D03*
X325378Y50351D03*
Y35351D03*
X310065Y32397D03*
X325364Y5500D03*
X320364D03*
X315364D03*
X310364D03*
X305364D03*
X300364D03*
X295364D03*
X290364D03*
X285364D03*
X280364D03*
X275364D03*
X270364D03*
X265364D03*
X270000Y29000D03*
Y33500D03*
Y38000D03*
Y42500D03*
X267188Y55192D03*
X285361Y78015D03*
X281761D03*
X289161Y58068D03*
X277514D03*
X295960Y148987D03*
Y154387D03*
X308907Y171800D03*
Y166400D03*
Y161000D03*
X287000Y117600D03*
Y125000D03*
X285500Y130400D03*
X290300D03*
X295100D03*
X272800Y168000D03*
Y172800D03*
Y134700D03*
X268000Y158700D03*
Y153900D03*
Y134700D03*
Y139500D03*
Y144300D03*
Y149100D03*
X296200Y195900D03*
Y190500D03*
X308907Y215200D03*
Y220600D03*
Y226000D03*
Y231400D03*
Y236800D03*
Y209800D03*
Y188200D03*
Y199000D03*
Y204400D03*
Y177200D03*
Y193600D03*
Y182800D03*
X296400Y237950D03*
Y232550D03*
X272800Y177600D03*
X268000Y235300D03*
Y230500D03*
Y225700D03*
Y220900D03*
Y216000D03*
Y211200D03*
Y206400D03*
Y201600D03*
X308907Y242200D03*
X266404Y249707D03*
X268000Y244900D03*
Y240100D03*
X388189Y48426D03*
X374016D03*
X359843D03*
X345670D03*
X388189Y34252D03*
X374016D03*
X359843D03*
X345670D03*
X388189Y20079D03*
X374016D03*
X359843D03*
X345670D03*
X388189Y5906D03*
X374016D03*
X359843D03*
X345670D03*
X381103Y38977D03*
X366929D03*
X352756D03*
X338583D03*
X381103Y24804D03*
X366929D03*
X352756D03*
X338583D03*
X381103Y53150D03*
X366929D03*
X352756D03*
X338583D03*
X330364Y5500D03*
X346700Y296333D03*
Y291533D03*
X444882Y48426D03*
X430709D03*
X416536D03*
X402363D03*
X444882Y34252D03*
X430709D03*
X416536D03*
X402363D03*
X444882Y20079D03*
X430709D03*
X416536D03*
X402363D03*
X444882Y5906D03*
X430709D03*
X416536D03*
X402363D03*
X437796Y38977D03*
X423622D03*
X409449D03*
X395276D03*
X437796Y24804D03*
X423622D03*
X409449D03*
X395276D03*
X437796Y53150D03*
X423622D03*
X409449D03*
X395276D03*
X433070Y236221D03*
X440944D03*
X448818D03*
X433070Y228347D03*
X440944D03*
X448818D03*
X405512Y212599D03*
X393701Y208662D03*
X401575D03*
X409449D03*
X417323D03*
X425197D03*
X433071D03*
X440945D03*
X448819D03*
X413386Y212599D03*
X421260D03*
X429134D03*
X437008D03*
X444882D03*
X437008Y275591D03*
X444882D03*
X501575Y48426D03*
X487402D03*
X473229D03*
X459055D03*
X501575Y34252D03*
X487402D03*
X473229D03*
X459055D03*
X501575Y20079D03*
X487402D03*
X473229D03*
X459055D03*
X501575Y5906D03*
X487402D03*
X473229D03*
X459055D03*
X508662Y38977D03*
X494489D03*
X480315D03*
X466142D03*
X451969D03*
X508662Y24804D03*
X494489D03*
X480315D03*
X466142D03*
X451969D03*
X508662Y53150D03*
X494489D03*
X480315D03*
X466142D03*
X451969D03*
X456693Y236221D03*
X464567D03*
X472441D03*
X460630Y208662D03*
X468504D03*
X484252D03*
X476378D03*
X496063D03*
X456693Y212599D03*
X464567D03*
X503937Y216536D03*
X472441Y212599D03*
X480315D03*
X488189D03*
X507874D03*
Y236221D03*
X503937Y232284D03*
X507874Y228347D03*
X503937Y224410D03*
X507874Y220473D03*
X472441Y228347D03*
X464567D03*
X456693D03*
X480315D03*
X484252Y236221D03*
X488189Y232284D03*
X503937Y255906D03*
X507874Y251969D03*
X503937Y248032D03*
X507874Y244095D03*
X503937Y240158D03*
X507874Y271654D03*
X503937Y267717D03*
X507874Y259843D03*
Y287402D03*
X503937Y283465D03*
X507874Y279528D03*
X503937Y275591D03*
Y299213D03*
X507874Y295276D03*
X503937Y291339D03*
X492126Y287402D03*
X484252Y271654D03*
Y279528D03*
X488189Y267717D03*
Y275591D03*
X492126Y271654D03*
Y279528D03*
X488189Y283465D03*
X484252Y259843D03*
Y251969D03*
Y244095D03*
X492126Y259843D03*
Y251969D03*
Y244095D03*
X456693Y255906D03*
X507874Y303150D03*
X481359Y347727D03*
X484252Y318898D03*
X492126D03*
X500000D03*
X496063Y307087D03*
X507874Y318898D03*
Y307087D03*
X511811D03*
X485100Y366800D03*
X490000Y363700D03*
X502850Y368500D03*
X572441Y48426D03*
X558268D03*
X544095D03*
X529922D03*
X515748D03*
X572441Y34252D03*
X558268D03*
X544095D03*
X529922D03*
X515748D03*
X572441Y20079D03*
X558268D03*
X544095D03*
X529922D03*
X515748D03*
X572441Y5906D03*
X558268D03*
X544095D03*
X529922D03*
X515748D03*
X565355Y38977D03*
X551181D03*
X537008D03*
X522835D03*
X565355Y24804D03*
X551181D03*
X537008D03*
X522835D03*
X565355Y53150D03*
X551181D03*
X537008D03*
X522835D03*
X515748Y318898D03*
Y307087D03*
X545880Y485940D03*
X586614Y48426D03*
Y34252D03*
Y20079D03*
Y5906D03*
X579528Y38977D03*
Y24804D03*
Y53150D03*
X591446Y6545D03*
X596446D03*
X601446D03*
X606446D03*
X611446D03*
X616446D03*
X621446D03*
X636446D03*
X631446D03*
X626446D03*
X635942Y97351D03*
X598600Y247800D03*
Y253100D03*
X590050Y337950D03*
X590200Y334350D03*
X641446Y6545D03*
X646446D03*
X651446D03*
X652551Y40716D03*
X696446Y6545D03*
X691446D03*
X661446D03*
X656446D03*
X686446D03*
X681446D03*
X676446D03*
X671446D03*
X666446D03*
X655914Y39932D03*
X667149Y23411D03*
X637003Y68809D03*
X648207Y70750D03*
X646643Y97859D03*
X670078Y170078D03*
X654330Y173228D03*
X651181Y166929D03*
X663779Y151181D03*
X666929Y148031D03*
X663779Y132283D03*
X651181Y141732D03*
Y132283D03*
Y122834D03*
Y192125D03*
X663779D03*
X657480D03*
X670078D03*
X654330Y185826D03*
Y179526D03*
X685826Y192125D03*
X692125D03*
X667353Y233486D03*
X678500Y240324D03*
X691100Y240354D03*
X686900D03*
X665520Y307707D03*
Y312507D03*
X660100Y307500D03*
X665478Y317527D03*
X694765Y406915D03*
X685750Y419460D03*
X694950Y477850D03*
Y473050D03*
X667414Y431956D03*
X667550Y565366D03*
X672550D03*
X677550D03*
X682550D03*
X687550D03*
X692550D03*
X697550D03*
X758267Y48426D03*
X744094D03*
X729921D03*
X715748D03*
X758267Y34252D03*
X744094D03*
X729921D03*
X715748D03*
X758267Y20079D03*
X744094D03*
X729921D03*
X715748D03*
X758267Y5906D03*
X744094D03*
X729921D03*
X715748D03*
X751181Y53150D03*
X737007D03*
X722834D03*
X708661D03*
X751181Y38977D03*
X737007D03*
X722834D03*
X708661D03*
X751181Y24804D03*
X737007D03*
X722834D03*
X708661D03*
X701446Y6545D03*
X728788Y88540D03*
X725295Y88609D03*
X752853Y100900D03*
X714173Y122834D03*
X720472D03*
X741077Y159790D03*
X757471Y148193D03*
X723621Y148031D03*
Y154330D03*
Y160629D03*
Y166929D03*
Y173228D03*
X707874Y122835D03*
X723621Y135433D03*
Y129133D03*
Y141732D03*
X701575Y122835D03*
X730737Y235199D03*
X724465Y224741D03*
X714620Y221041D03*
X743460Y231900D03*
X701574Y192125D03*
X707873D03*
X714173D03*
X723621D03*
Y185826D03*
Y179527D03*
X707574Y276558D03*
X712720Y240976D03*
X705320Y420610D03*
X718110Y442960D03*
X708355Y454712D03*
X719920Y429700D03*
X740900Y476400D03*
Y469400D03*
Y461900D03*
X702550Y565366D03*
X707550D03*
X712550D03*
X717550D03*
X722550D03*
X727550D03*
X732550D03*
X737550D03*
X742550D03*
X747550D03*
X752550D03*
X757550D03*
X821272Y49340D03*
Y44340D03*
Y39340D03*
Y34340D03*
Y29340D03*
Y24340D03*
Y19340D03*
Y14340D03*
Y9340D03*
X815364Y5500D03*
X810364D03*
X805364D03*
X800364D03*
X795364D03*
X790364D03*
X785364D03*
X780364D03*
X775364D03*
X770364D03*
X765364D03*
X799250Y71125D03*
X821272Y99340D03*
Y94340D03*
Y89340D03*
Y84340D03*
Y79340D03*
Y74340D03*
Y69340D03*
Y64340D03*
Y59340D03*
Y54340D03*
X772107Y83046D03*
X799493Y93250D03*
X804320Y134300D03*
X804400Y175000D03*
X760800Y169550D03*
X769600Y164200D03*
X765200Y135750D03*
X786500Y134283D03*
X763050Y154100D03*
X761400Y160050D03*
X764600Y141500D03*
X764550Y182900D03*
X764750Y179300D03*
X761550Y180500D03*
X793837Y291696D03*
X821272Y484340D03*
Y504340D03*
Y509340D03*
Y514340D03*
Y519340D03*
Y524340D03*
Y529340D03*
Y549340D03*
Y544340D03*
Y539340D03*
Y534340D03*
Y499340D03*
Y494340D03*
Y489340D03*
X762550Y565366D03*
X767550D03*
X772550D03*
X777550D03*
X782550D03*
X787550D03*
X792550D03*
X797550D03*
X802550D03*
X807550D03*
X812550D03*
X817550D03*
X821272Y559340D03*
Y554340D03*
G54D24*
X145900Y136500D03*
G54D25*
X234450Y73000D03*
X381103Y10651D03*
X366929D03*
X352756D03*
X338583D03*
X437796D03*
X423622D03*
X409449D03*
X395276D03*
X425196Y228347D03*
X508661Y10651D03*
X494488D03*
X480315D03*
X466142D03*
X451969D03*
X565354D03*
X551181D03*
X537008D03*
X522835D03*
X579527D03*
X618300Y327654D03*
X663778Y144883D03*
Y138584D03*
X654642Y312507D03*
X654488Y317417D03*
X654642Y307707D03*
X751181Y10651D03*
X737007D03*
X722834D03*
X708661D03*
G54D18*
X37402Y535158D03*
X789370D03*
G54D19*
X116063Y14567D03*
G54D10*
X15812Y-86244D03*
X27058Y25484D03*
X81539Y542850D03*
X411652Y539991D03*
X812711Y-86834D03*
X798456Y26432D03*
G54D31*
X389764Y460630D03*
X437008D03*
G54D20*
X116063Y39075D03*
G54D29*
X374015Y156220D03*
X531496Y371299D03*
X596456Y116142D03*
X781496Y198818D03*
G54D16*
X37402Y517441D03*
X789370D03*
G54D27*
X295275Y531496D03*
X531495D03*
G54D14*
X38502Y161319D03*
X49302D03*
X43902D03*
X49302Y150519D03*
Y155919D03*
X43902Y150519D03*
Y155919D03*
X38502D03*
Y150519D03*
X22150Y203550D03*
X26150Y230850D03*
X296385Y108227D03*
X464568Y275592D03*
X542627Y324049D03*
X555127D03*
X541278Y315738D03*
X553778D03*
X541221Y308771D03*
X553721D03*
X629813Y27661D03*
X594025Y284017D03*
X610750Y336850D03*
X594050Y301755D03*
X598152Y370130D03*
X656450Y28000D03*
X672800Y438832D03*
X696950Y441400D03*
X725247Y458974D03*
X724422Y464139D03*
X724400Y485200D03*
Y480400D03*
Y475600D03*
X701120Y430620D03*
X724400Y490200D03*
G54D21*
X108672Y138471D03*
Y132871D03*
X90672Y138471D03*
X102672D03*
X96672D03*
X84672D03*
Y132871D03*
X96672D03*
X102672D03*
X90672D03*
X229000Y95000D03*
X704115Y414466D03*
Y409666D03*
Y404866D03*
Y400066D03*
X760715Y197200D03*
X781640Y282160D03*
G54D32*
X437007Y267718D03*
X448818Y255906D03*
Y263780D03*
Y271655D03*
X440944Y263780D03*
Y271655D03*
X437007Y259843D03*
X440944Y255906D03*
X460630Y275592D03*
X452756D03*
X464567Y255906D03*
Y263780D03*
X456693D03*
X464567Y271655D03*
X456693D03*
G54D33*
X437007Y255905D03*
G54D26*
X248169Y74454D03*
X425197Y236220D03*
X612300Y356850D03*
X608500Y315000D03*
G54D35*
X590537Y170119D03*
X586912Y154495D03*
X584314Y166721D03*
X596233Y145667D03*
X593635Y157893D03*
X588901Y134308D03*
X586303Y146534D03*
X577699Y123469D03*
X575101Y135695D03*
X589966Y210195D03*
X587368Y222421D03*
X585841Y194571D03*
X583243Y206797D03*
X581716Y178947D03*
X579118Y191173D03*
X587939Y182345D03*
%LPC*%
G75*
G54D36*
G01X-34018Y-300855D02*
G02I-12000J0D01*
G01X-39168D02*
G02I-6850J0D01*
G01X-30018D02*
X-62018D01*
G01X-30018Y-316855D02*
Y-396855D01*
G01D02*
X1320682D01*
G01X-30018Y-352355D02*
X1320682D01*
G01X-46018Y-316855D02*
Y-284855D01*
G01X-30018Y-316855D02*
X1320682D01*
G01X533182D02*
Y-396855D01*
G01X670682Y-316855D02*
Y-396855D01*
G01X785682Y-316855D02*
Y-396855D01*
G01X953182Y-316855D02*
Y-396855D01*
G01X1123182Y-316855D02*
Y-396855D01*
G01X1320682Y-316855D02*
Y-396855D01*
G01X1348682Y-300855D02*
G02I-12000J0D01*
G01X1343532D02*
G02I-6850J0D01*
G01X1336682Y-316855D02*
Y-284855D01*
G01X1352682Y-300855D02*
X1320682D01*
G54D37*
G01X121778Y-377522D02*
X122652Y-376647D01*
X123307Y-375189D01*
X123744Y-373146D01*
X123307Y-371397D01*
X122434Y-370230D01*
X120905Y-369355D01*
X115010D01*
Y-386855D01*
X122215D01*
X123744Y-385689D01*
X124617Y-383938D01*
X125054Y-381897D01*
X124617Y-379855D01*
X123307Y-378105D01*
X121778Y-377522D01*
X115010D01*
G01X134475Y-386855D02*
Y-375189D01*
G01Y-377522D02*
X135567Y-376355D01*
X136659Y-375480D01*
X138187Y-375189D01*
X139278Y-375480D01*
X140589Y-376355D01*
G01X150447Y-392105D02*
X151757Y-392688D01*
X153504Y-392105D01*
X154595Y-390939D01*
X155469Y-389480D01*
X156778Y-384814D01*
X159617Y-375189D01*
G01X152630D02*
X156778Y-384814D01*
G01X176025Y-376647D02*
X174497Y-375480D01*
X173187Y-375189D01*
X171440Y-375772D01*
X170130Y-376938D01*
X169257Y-378980D01*
X169038Y-381022D01*
X169257Y-383064D01*
X170130Y-384814D01*
X171440Y-386272D01*
X173187Y-386855D01*
X174715Y-386272D01*
X176025Y-385105D01*
G01X186757Y-378980D02*
X193744D01*
X193089Y-376938D01*
X191997Y-375772D01*
X190469Y-375189D01*
X188940Y-375480D01*
X187630Y-376355D01*
X186757Y-378397D01*
X186320Y-380147D01*
Y-381897D01*
X186757Y-383647D01*
X187849Y-385397D01*
X189159Y-386563D01*
X190687Y-386855D01*
X192215Y-386272D01*
X193744Y-384522D01*
G01X229835Y-370814D02*
X228525Y-369938D01*
X226997Y-369355D01*
X225250D01*
X223285Y-370230D01*
X221757Y-371688D01*
X220665Y-373439D01*
X219792Y-376355D01*
X219573Y-378980D01*
X220010Y-381605D01*
X220665Y-383355D01*
X221975Y-385105D01*
X223504Y-386272D01*
X225032Y-386855D01*
X226560D01*
X228089Y-386272D01*
X229399Y-385397D01*
X230491Y-384231D01*
G01X246462Y-386855D02*
Y-375189D01*
G01Y-377230D02*
X245589Y-376064D01*
X244278Y-375480D01*
X242750Y-375189D01*
X241222Y-375772D01*
X239912Y-376938D01*
X239038Y-378688D01*
X238602Y-381022D01*
X239038Y-383355D01*
X239912Y-385105D01*
X241222Y-386272D01*
X242750Y-386855D01*
X244278Y-386563D01*
X245589Y-385689D01*
X246462Y-384522D01*
G01X256320Y-386855D02*
Y-375189D01*
G01Y-378105D02*
X257194Y-376647D01*
X258504Y-375480D01*
X260250Y-375189D01*
X261778Y-375480D01*
X263089Y-376647D01*
X263744Y-378688D01*
Y-386855D01*
G01X272947Y-392105D02*
X274257Y-392688D01*
X276004Y-392105D01*
X277095Y-390939D01*
X277969Y-389480D01*
X279278Y-384814D01*
X282117Y-375189D01*
G01X275130D02*
X279278Y-384814D01*
G01X295032Y-386855D02*
X293722Y-386563D01*
X292412Y-385397D01*
X291538Y-383355D01*
X291102Y-381022D01*
X291538Y-378688D01*
X292412Y-376647D01*
X293722Y-375480D01*
X295032Y-375189D01*
X296342Y-375480D01*
X297652Y-376647D01*
X298525Y-378688D01*
X298744Y-381022D01*
X298525Y-383355D01*
X297652Y-385397D01*
X296342Y-386563D01*
X295032Y-386855D01*
G01X308820D02*
Y-375189D01*
G01Y-378105D02*
X309694Y-376647D01*
X311004Y-375480D01*
X312750Y-375189D01*
X314278Y-375480D01*
X315589Y-376647D01*
X316244Y-378688D01*
Y-386855D01*
G01X342947Y-384522D02*
X344694Y-385980D01*
X346659Y-386855D01*
X348405D01*
X350152Y-385980D01*
X351462Y-384522D01*
X352117Y-382480D01*
X351680Y-380439D01*
X350589Y-378688D01*
X348624Y-377522D01*
X346004Y-376938D01*
X344475Y-375772D01*
X343820Y-373730D01*
X344257Y-371688D01*
X345349Y-370230D01*
X346877Y-369355D01*
X348405D01*
X349934Y-369938D01*
X351244Y-371397D01*
G01X369835Y-370814D02*
X368525Y-369938D01*
X366997Y-369355D01*
X365250D01*
X363285Y-370230D01*
X361757Y-371688D01*
X360665Y-373439D01*
X359792Y-376355D01*
X359573Y-378980D01*
X360010Y-381605D01*
X360665Y-383355D01*
X361975Y-385105D01*
X363504Y-386272D01*
X365032Y-386855D01*
X366560D01*
X368089Y-386272D01*
X369399Y-385397D01*
X370491Y-384231D01*
G01X387335Y-370814D02*
X386025Y-369938D01*
X384497Y-369355D01*
X382750D01*
X380785Y-370230D01*
X379257Y-371688D01*
X378165Y-373439D01*
X377292Y-376355D01*
X377073Y-378980D01*
X377510Y-381605D01*
X378165Y-383355D01*
X379475Y-385105D01*
X381004Y-386272D01*
X382532Y-386855D01*
X384060D01*
X385589Y-386272D01*
X386899Y-385397D01*
X387991Y-384231D01*
G01X210605Y-341855D02*
Y-324355D01*
X216282Y-338938D01*
X221959Y-324355D01*
Y-341855D01*
G01X233782D02*
X232472Y-341563D01*
X231162Y-340397D01*
X230288Y-338355D01*
X229852Y-336022D01*
X230288Y-333688D01*
X231162Y-331647D01*
X232472Y-330480D01*
X233782Y-330189D01*
X235092Y-330480D01*
X236402Y-331647D01*
X237275Y-333688D01*
X237494Y-336022D01*
X237275Y-338355D01*
X236402Y-340397D01*
X235092Y-341563D01*
X233782Y-341855D01*
G01X255212Y-324355D02*
Y-341855D01*
G01Y-339231D02*
X254339Y-340689D01*
X253028Y-341563D01*
X251500Y-341855D01*
X249754Y-341272D01*
X248444Y-339814D01*
X247570Y-338064D01*
X247352Y-336022D01*
X247570Y-333980D01*
X248444Y-332230D01*
X249754Y-330772D01*
X251500Y-330189D01*
X253028Y-330480D01*
X254120Y-331064D01*
X255212Y-332230D01*
G01X265507Y-333980D02*
X272494D01*
X271839Y-331938D01*
X270747Y-330772D01*
X269219Y-330189D01*
X267690Y-330480D01*
X266380Y-331355D01*
X265507Y-333397D01*
X265070Y-335147D01*
Y-336897D01*
X265507Y-338647D01*
X266599Y-340397D01*
X267909Y-341563D01*
X269437Y-341855D01*
X270965Y-341272D01*
X272494Y-339522D01*
G01X286282Y-341855D02*
Y-324355D01*
G01X566882Y-386855D02*
Y-369355D01*
X564262Y-372855D01*
G01Y-386855D02*
X569502D01*
G01X580234Y-379564D02*
X581762Y-377522D01*
X583072Y-376355D01*
X584819Y-375772D01*
X586347Y-376355D01*
X587439Y-377522D01*
X588312Y-379272D01*
X588530Y-381313D01*
X588312Y-383064D01*
X587439Y-384814D01*
X586128Y-386272D01*
X584600Y-386855D01*
X582854Y-386272D01*
X581325Y-384522D01*
X580452Y-381897D01*
X580234Y-378980D01*
X580670Y-375189D01*
X581325Y-373146D01*
X582417Y-371105D01*
X583945Y-369647D01*
X585474Y-369355D01*
X587002Y-369938D01*
X588094Y-371397D01*
G01X597079Y-383355D02*
X598388Y-385397D01*
X600135Y-386563D01*
X602100Y-386855D01*
X603847Y-386563D01*
X605594Y-385105D01*
X606685Y-383355D01*
X606904Y-381605D01*
X606467Y-379564D01*
X604939Y-378105D01*
X603410Y-377522D01*
X601445D01*
G01X603410D02*
X604720Y-376647D01*
X605812Y-375189D01*
X606249Y-373439D01*
X605812Y-371688D01*
X604720Y-370230D01*
X602755Y-369355D01*
X600790Y-369647D01*
X598825Y-370814D01*
G01X619382Y-386855D02*
Y-369355D01*
X616762Y-372855D01*
G01Y-386855D02*
X622002D01*
G01X632734Y-379564D02*
X634262Y-377522D01*
X635572Y-376355D01*
X637319Y-375772D01*
X638847Y-376355D01*
X639939Y-377522D01*
X640812Y-379272D01*
X641030Y-381313D01*
X640812Y-383064D01*
X639939Y-384814D01*
X638628Y-386272D01*
X637100Y-386855D01*
X635354Y-386272D01*
X633825Y-384522D01*
X632952Y-381897D01*
X632734Y-378980D01*
X633170Y-375189D01*
X633825Y-373146D01*
X634917Y-371105D01*
X636445Y-369647D01*
X637974Y-369355D01*
X639502Y-369938D01*
X640594Y-371397D01*
G01X553765Y-341855D02*
Y-324355D01*
X559005D01*
X560752Y-325230D01*
X562062Y-327272D01*
X562499Y-329605D01*
X562062Y-331938D01*
X560970Y-333688D01*
X559005Y-334564D01*
X553765D01*
G01X580435Y-325814D02*
X579125Y-324938D01*
X577597Y-324355D01*
X575850D01*
X573885Y-325230D01*
X572357Y-326688D01*
X571265Y-328439D01*
X570392Y-331355D01*
X570173Y-333980D01*
X570610Y-336605D01*
X571265Y-338355D01*
X572575Y-340105D01*
X574104Y-341272D01*
X575632Y-341855D01*
X577160D01*
X578689Y-341272D01*
X579999Y-340397D01*
X581091Y-339231D01*
G01X594878Y-332522D02*
X595752Y-331647D01*
X596407Y-330189D01*
X596844Y-328146D01*
X596407Y-326397D01*
X595534Y-325230D01*
X594005Y-324355D01*
X588110D01*
Y-341855D01*
X595315D01*
X596844Y-340689D01*
X597717Y-338938D01*
X598154Y-336897D01*
X597717Y-334855D01*
X596407Y-333105D01*
X594878Y-332522D01*
X588110D01*
G01X604082Y-347688D02*
X617182D01*
G01X623110Y-341855D02*
Y-324355D01*
X633154Y-341855D01*
Y-324355D01*
G01X645632Y-341855D02*
X643885Y-341563D01*
X642357Y-340397D01*
X641047Y-338647D01*
X640173Y-336605D01*
X639737Y-334272D01*
Y-331938D01*
X640173Y-329605D01*
X641047Y-327563D01*
X642357Y-325814D01*
X643885Y-324647D01*
X645632Y-324355D01*
X647378Y-324647D01*
X648907Y-325814D01*
X650217Y-327563D01*
X651091Y-329605D01*
X651527Y-331938D01*
Y-334272D01*
X651091Y-336605D01*
X650217Y-338647D01*
X648907Y-340397D01*
X647378Y-341563D01*
X645632Y-341855D01*
G01X696473Y-324355D02*
X701932Y-341855D01*
X707391Y-324355D01*
G01X723799Y-341855D02*
X715065D01*
Y-324355D01*
X723799D01*
G01X720305Y-332813D02*
X715065D01*
G01X732565Y-341855D02*
Y-324355D01*
X738024D01*
X739770Y-325230D01*
X740862Y-326397D01*
X741299Y-328730D01*
X740862Y-331064D01*
X739552Y-332522D01*
X738024Y-333397D01*
X732565D01*
G01X738024D02*
X741299Y-341855D01*
G01X754432Y-342438D02*
X753995Y-342147D01*
Y-341563D01*
X754432Y-341272D01*
X754869Y-341563D01*
Y-342147D01*
X754432Y-342438D01*
G01X728182Y-386855D02*
Y-369355D01*
X725562Y-372855D01*
G01Y-386855D02*
X730802D01*
G01X830015Y-369355D02*
Y-386855D01*
X838749D01*
G01X854502D02*
Y-369355D01*
X846423Y-381897D01*
X857341D01*
G01X863923Y-369355D02*
X869382Y-386855D01*
X874841Y-369355D01*
G01X891685Y-370814D02*
X890375Y-369938D01*
X888847Y-369355D01*
X887100D01*
X885135Y-370230D01*
X883607Y-371688D01*
X882515Y-373439D01*
X881642Y-376355D01*
X881423Y-378980D01*
X881860Y-381605D01*
X882515Y-383355D01*
X883825Y-385105D01*
X885354Y-386272D01*
X886882Y-386855D01*
X888410D01*
X889939Y-386272D01*
X891249Y-385397D01*
X892341Y-384231D01*
G01X909185Y-370814D02*
X907875Y-369938D01*
X906347Y-369355D01*
X904600D01*
X902635Y-370230D01*
X901107Y-371688D01*
X900015Y-373439D01*
X899142Y-376355D01*
X898923Y-378980D01*
X899360Y-381605D01*
X900015Y-383355D01*
X901325Y-385105D01*
X902854Y-386272D01*
X904382Y-386855D01*
X905910D01*
X907439Y-386272D01*
X908749Y-385397D01*
X909841Y-384231D01*
G01X830015Y-324355D02*
Y-341855D01*
X838749D01*
G01X855812D02*
Y-330189D01*
G01Y-332230D02*
X854939Y-331064D01*
X853628Y-330480D01*
X852100Y-330189D01*
X850572Y-330772D01*
X849262Y-331938D01*
X848388Y-333688D01*
X847952Y-336022D01*
X848388Y-338355D01*
X849262Y-340105D01*
X850572Y-341272D01*
X852100Y-341855D01*
X853628Y-341563D01*
X854939Y-340689D01*
X855812Y-339522D01*
G01X864797Y-347105D02*
X866107Y-347688D01*
X867854Y-347105D01*
X868945Y-345939D01*
X869819Y-344480D01*
X871128Y-339814D01*
X873967Y-330189D01*
G01X866980D02*
X871128Y-339814D01*
G01X883607Y-333980D02*
X890594D01*
X889939Y-331938D01*
X888847Y-330772D01*
X887319Y-330189D01*
X885790Y-330480D01*
X884480Y-331355D01*
X883607Y-333397D01*
X883170Y-335147D01*
Y-336897D01*
X883607Y-338647D01*
X884699Y-340397D01*
X886009Y-341563D01*
X887537Y-341855D01*
X889065Y-341272D01*
X890594Y-339522D01*
G01X901325Y-341855D02*
Y-330189D01*
G01Y-332522D02*
X902417Y-331355D01*
X903509Y-330480D01*
X905037Y-330189D01*
X906128Y-330480D01*
X907439Y-331355D01*
G01X994432Y-386855D02*
X992685Y-386563D01*
X991157Y-385397D01*
X989847Y-383647D01*
X988973Y-381605D01*
X988537Y-379272D01*
Y-376938D01*
X988973Y-374605D01*
X989847Y-372563D01*
X991157Y-370814D01*
X992685Y-369647D01*
X994432Y-369355D01*
X996178Y-369647D01*
X997707Y-370814D01*
X999017Y-372563D01*
X999891Y-374605D01*
X1000327Y-376938D01*
Y-379272D01*
X999891Y-381605D01*
X999017Y-383647D01*
X997707Y-385397D01*
X996178Y-386563D01*
X994432Y-386855D01*
G01X996178Y-382188D02*
X998799Y-386855D01*
G01X1007129Y-369355D02*
Y-381897D01*
X1008002Y-384522D01*
X1009749Y-386272D01*
X1011932Y-386855D01*
X1014115Y-386272D01*
X1015862Y-384522D01*
X1016735Y-381897D01*
Y-369355D01*
G01X1026812D02*
X1032052D01*
G01X1029432D02*
Y-386855D01*
G01X1026812D02*
X1032052D01*
G01X1041910D02*
Y-369355D01*
X1051954Y-386855D01*
Y-369355D01*
G01X1069235Y-370814D02*
X1067925Y-369938D01*
X1066397Y-369355D01*
X1064650D01*
X1062685Y-370230D01*
X1061157Y-371688D01*
X1060065Y-373439D01*
X1059192Y-376355D01*
X1058973Y-378980D01*
X1059410Y-381605D01*
X1060065Y-383355D01*
X1061375Y-385105D01*
X1062904Y-386272D01*
X1064432Y-386855D01*
X1065960D01*
X1067489Y-386272D01*
X1068799Y-385397D01*
X1069891Y-384231D01*
G01X1081932Y-386855D02*
Y-378980D01*
X1077565Y-369355D01*
G01X1086299D02*
X1081932Y-378980D01*
G01X972129Y-341855D02*
Y-324355D01*
X976495D01*
X978242Y-325230D01*
X979552Y-326397D01*
X980644Y-328146D01*
X981517Y-330189D01*
X981735Y-333105D01*
X981517Y-336022D01*
X980644Y-338064D01*
X979552Y-339814D01*
X978242Y-340980D01*
X976495Y-341855D01*
X972129D01*
G01X991157Y-333980D02*
X998144D01*
X997489Y-331938D01*
X996397Y-330772D01*
X994869Y-330189D01*
X993340Y-330480D01*
X992030Y-331355D01*
X991157Y-333397D01*
X990720Y-335147D01*
Y-336897D01*
X991157Y-338647D01*
X992249Y-340397D01*
X993559Y-341563D01*
X995087Y-341855D01*
X996615Y-341272D01*
X998144Y-339522D01*
G01X1008657Y-339814D02*
X1009749Y-340980D01*
X1011277Y-341855D01*
X1012587D01*
X1013897Y-341272D01*
X1014770Y-340397D01*
X1015207Y-339231D01*
X1014989Y-337480D01*
X1014115Y-336605D01*
X1010185Y-334855D01*
X1009312Y-332813D01*
X1009749Y-331355D01*
X1010622Y-330480D01*
X1011932Y-330189D01*
X1013242Y-330480D01*
X1014552Y-331355D01*
G01X1029432Y-330189D02*
Y-341855D01*
G01Y-325522D02*
X1028995Y-325230D01*
Y-324647D01*
X1029432Y-324355D01*
X1029869Y-324647D01*
Y-325230D01*
X1029432Y-325522D01*
G01X1043875Y-346230D02*
X1045404Y-347397D01*
X1047150Y-347688D01*
X1048678Y-347397D01*
X1049989Y-345939D01*
X1050862Y-343897D01*
Y-330189D01*
G01Y-332522D02*
X1049989Y-331355D01*
X1048678Y-330480D01*
X1047150Y-330189D01*
X1045404Y-330772D01*
X1044312Y-331938D01*
X1043438Y-333980D01*
X1043002Y-336022D01*
X1043220Y-337772D01*
X1044094Y-339814D01*
X1045404Y-341272D01*
X1047150Y-341855D01*
X1048460Y-341563D01*
X1049989Y-340397D01*
X1050862Y-339231D01*
G01X1060720Y-341855D02*
Y-330189D01*
G01Y-333105D02*
X1061594Y-331647D01*
X1062904Y-330480D01*
X1064650Y-330189D01*
X1066178Y-330480D01*
X1067489Y-331647D01*
X1068144Y-333688D01*
Y-341855D01*
G01X1078657Y-333980D02*
X1085644D01*
X1084989Y-331938D01*
X1083897Y-330772D01*
X1082369Y-330189D01*
X1080840Y-330480D01*
X1079530Y-331355D01*
X1078657Y-333397D01*
X1078220Y-335147D01*
Y-336897D01*
X1078657Y-338647D01*
X1079749Y-340397D01*
X1081059Y-341563D01*
X1082587Y-341855D01*
X1084115Y-341272D01*
X1085644Y-339522D01*
G01X1096375Y-341855D02*
Y-330189D01*
G01Y-332522D02*
X1097467Y-331355D01*
X1098559Y-330480D01*
X1100087Y-330189D01*
X1101178Y-330480D01*
X1102489Y-331355D01*
G01X1143132Y-369355D02*
X1141385Y-369938D01*
X1140075Y-371397D01*
X1139202Y-373146D01*
X1138547Y-375480D01*
X1138329Y-378105D01*
X1138547Y-380730D01*
X1139202Y-383064D01*
X1140075Y-384814D01*
X1141385Y-386272D01*
X1143132Y-386855D01*
X1144878Y-386272D01*
X1146189Y-384814D01*
X1147062Y-383064D01*
X1147717Y-380730D01*
X1147935Y-378105D01*
X1147717Y-375480D01*
X1147062Y-373146D01*
X1146189Y-371397D01*
X1144878Y-369938D01*
X1143132Y-369355D01*
G01X1156484Y-379564D02*
X1158012Y-377522D01*
X1159322Y-376355D01*
X1161069Y-375772D01*
X1162597Y-376355D01*
X1163689Y-377522D01*
X1164562Y-379272D01*
X1164780Y-381313D01*
X1164562Y-383064D01*
X1163689Y-384814D01*
X1162378Y-386272D01*
X1160850Y-386855D01*
X1159104Y-386272D01*
X1157575Y-384522D01*
X1156702Y-381897D01*
X1156484Y-378980D01*
X1156920Y-375189D01*
X1157575Y-373146D01*
X1158667Y-371105D01*
X1160195Y-369647D01*
X1161724Y-369355D01*
X1163252Y-369938D01*
X1164344Y-371397D01*
G01X1174202Y-387438D02*
X1182062Y-369355D01*
G01X1191484Y-372272D02*
X1192794Y-370522D01*
X1194322Y-369647D01*
X1196069Y-369355D01*
X1198252Y-369938D01*
X1199780Y-371397D01*
X1200217Y-373146D01*
X1199999Y-374897D01*
X1199125Y-376355D01*
X1194759Y-379272D01*
X1192794Y-381313D01*
X1191484Y-384231D01*
X1191047Y-386855D01*
X1200217D01*
G01X1213132D02*
Y-369355D01*
X1210512Y-372855D01*
G01Y-386855D02*
X1215752D01*
G01X1226702Y-387438D02*
X1234562Y-369355D01*
G01X1243984Y-372272D02*
X1245294Y-370522D01*
X1246822Y-369647D01*
X1248569Y-369355D01*
X1250752Y-369938D01*
X1252280Y-371397D01*
X1252717Y-373146D01*
X1252499Y-374897D01*
X1251625Y-376355D01*
X1247259Y-379272D01*
X1245294Y-381313D01*
X1243984Y-384231D01*
X1243547Y-386855D01*
X1252717D01*
G01X1265632Y-369355D02*
X1263885Y-369938D01*
X1262575Y-371397D01*
X1261702Y-373146D01*
X1261047Y-375480D01*
X1260829Y-378105D01*
X1261047Y-380730D01*
X1261702Y-383064D01*
X1262575Y-384814D01*
X1263885Y-386272D01*
X1265632Y-386855D01*
X1267378Y-386272D01*
X1268689Y-384814D01*
X1269562Y-383064D01*
X1270217Y-380730D01*
X1270435Y-378105D01*
X1270217Y-375480D01*
X1269562Y-373146D01*
X1268689Y-371397D01*
X1267378Y-369938D01*
X1265632Y-369355D01*
G01X1283132Y-386855D02*
Y-369355D01*
X1280512Y-372855D01*
G01Y-386855D02*
X1285752D01*
G01X1300195D02*
X1300632Y-383064D01*
X1301287Y-379855D01*
X1302160Y-376938D01*
X1303252Y-373730D01*
X1304999Y-369355D01*
X1296265D01*
G01X1190829Y-341855D02*
Y-324355D01*
X1195195D01*
X1196942Y-325230D01*
X1198252Y-326397D01*
X1199344Y-328146D01*
X1200217Y-330189D01*
X1200435Y-333105D01*
X1200217Y-336022D01*
X1199344Y-338064D01*
X1198252Y-339814D01*
X1196942Y-340980D01*
X1195195Y-341855D01*
X1190829D01*
G01X1217062D02*
Y-330189D01*
G01Y-332230D02*
X1216189Y-331064D01*
X1214878Y-330480D01*
X1213350Y-330189D01*
X1211822Y-330772D01*
X1210512Y-331938D01*
X1209638Y-333688D01*
X1209202Y-336022D01*
X1209638Y-338355D01*
X1210512Y-340105D01*
X1211822Y-341272D01*
X1213350Y-341855D01*
X1214878Y-341563D01*
X1216189Y-340689D01*
X1217062Y-339522D01*
G01X1230632Y-324355D02*
Y-341855D01*
G01X1227575Y-330189D02*
X1233689D01*
G01X1244857Y-333980D02*
X1251844D01*
X1251189Y-331938D01*
X1250097Y-330772D01*
X1248569Y-330189D01*
X1247040Y-330480D01*
X1245730Y-331355D01*
X1244857Y-333397D01*
X1244420Y-335147D01*
Y-336897D01*
X1244857Y-338647D01*
X1245949Y-340397D01*
X1247259Y-341563D01*
X1248787Y-341855D01*
X1250315Y-341272D01*
X1251844Y-339522D01*
M02*
